G04 ================== begin FILE IDENTIFICATION RECORD ==================*
G04 Layout Name:  F:/<user>/2022/FB/R4006-TIMING/brd/gerber-3/R4006-B0001-02_R01.brd*
G04 Film Name:    R4006-B0001-02_R01_L08*
G04 File Format:  Gerber RS274X*
G04 File Origin:  Cadence Allegro 17.2-S079*
G04 Origin Date:  Fri Feb 25 18:14:43 2022*
G04 *
G04 Layer:  ETCH/L08_SIG2*
G04 Layer:  PIN/L08_SIG2*
G04 Layer:  VIA CLASS/L08_SIG2*
G04 Layer:  MANUFACTURING/L08_SIG2*
G04 Layer:  MANUFACTURING/CELESTICA_LEGEND*
G04 *
G04 Offset:    (0.00 0.00)*
G04 Mirror:    No*
G04 Mode:      Positive*
G04 Rotation:  0*
G04 FullContactRelief:  No*
G04 UndefLineWidth:     6.00*
G04 ================== end FILE IDENTIFICATION RECORD ====================*
%FSLAX55Y55*MOIN*%
%IR0*IPPOS*OFA0.00000B0.00000*MIA0B0*SFA1.00000B1.00000*%
%ADD10C,.02*%
%ADD11C,.024*%
%ADD12C,.018*%
%ADD13C,.01*%
%ADD14C,.015*%
%ADD15C,.004*%
%ADD16C,.006*%
%ADD17C,.005*%
%ADD18C,.0035*%
%ADD19C,.0062*%
%ADD20C,.0045*%
%ADD21C,.0046*%
%ADD22C,.06004*%
G75*
%LPD*%
G75*
G36*
G01X141263Y374000D02*
X141500D01*
X145033Y370467D01*
X145021Y370370D01*
G03X144998Y370000I2979J-371D01*
G03X148000Y366998I3002J0D01*
G03X148370Y367021I-1J3002D01*
G01X148467Y367033D01*
X149000Y366500D01*
Y359662D01*
G03X148498Y358000I2500J-1662D01*
G03X151423Y354999I3002J0D01*
G01X151503Y354997D01*
X156097Y350403D01*
X156099Y350323D01*
G03X159023Y347399I3001J77D01*
G01X159103Y347397D01*
X163000Y343500D01*
Y317000D01*
X157075Y311075D01*
G02X156405Y311257I-283J283D01*
G03X153500Y313502I-2905J-757D01*
G03X151794Y312970I0J-3001D01*
G03X149500Y314036I-2294J-1935D01*
G03X146564Y311660I0J-3002D01*
G01X146530Y311502D01*
X138401D01*
G02X138001Y311913I0J400D01*
G03X138002Y312000I-3001J78D01*
G03X131998I-3002J0D01*
G03X131999Y311913I3002J-9D01*
G02X131599Y311502I-400J-11D01*
G01X131499D01*
X130000Y313000D01*
X97464D01*
X97429Y313156D01*
G03X91571I-2929J-655D01*
G01X91536Y313000D01*
X83500D01*
X81361Y310861D01*
X81224Y310958D01*
G03X79500Y311502I-1723J-2458D01*
G03X76571Y309156I0J-3001D01*
G01X76536Y309000D01*
X64239D01*
G03X59761I-2239J-2001D01*
G01X53500D01*
X45000Y317500D01*
X43106D01*
G03X43000Y317502I-110J-3000D01*
G03X42894Y317500I4J-3002D01*
G01X39000D01*
X30738Y325762D01*
X30787Y325884D01*
G03X31002Y327000I-2787J1116D01*
G03X28000Y330002I-3002J0D01*
G03X25906Y329151I0J-3002D01*
G02X25345Y329155I-278J287D01*
G01X25000Y329500D01*
Y332234D01*
X26807D01*
G03X30558Y335985I0J3751D01*
G03X30020Y337921I-3752J0D01*
G02X30275Y338517I343J206D01*
G03X31340Y339335I-354J1563D01*
G02X32048I354J-187D01*
G03X34884I1418J745D01*
G02X35592I354J-187D01*
G03X37010Y338478I1418J745D01*
G03X38612Y340080I0J1602D01*
G03X38364Y340936I-1601J0D01*
G02X38718Y341549I338J213D01*
G03X38782Y341548I57J1601D01*
G03Y344752I0J1602D01*
G03X37364Y343895I0J-1602D01*
G02X36656I-354J187D01*
G03X33820I-1418J-745D01*
G02X33112I-354J187D01*
G03X31694Y344752I-1418J-745D01*
G03X30092Y343150I0J-1602D01*
G03X30340Y342294I1601J0D01*
G02X29986Y341681I-338J-213D01*
G03X29922Y341682I-57J-1601D01*
G03X28320Y340080I0J-1602D01*
G03X28322Y340003I1602J3D01*
G02X27815Y339599I-399J-19D01*
G03X26807Y339736I-1005J-3614D01*
G01X25000D01*
Y341591D01*
X25134Y341638D01*
G03X26207Y343105I-528J1512D01*
G02X26607Y343494I400J-11D01*
G01X26807D01*
G03X30558Y347245I0J3751D01*
G03X29975Y349254I-3751J1D01*
G01X29889Y349389D01*
X31749Y351248D01*
X37500D01*
G03X37763Y351264I-5J2252D01*
G02X37985Y351091I24J-199D01*
G03X41705Y347824I3720J484D01*
G01X45705D01*
G03X49451Y351379I0J3751D01*
G01X49455Y351455D01*
X51851Y353851D01*
G02X52471Y353783I283J-283D01*
G03X55000Y352398I2529J1616D01*
G03X58001Y355306I0J3002D01*
G01X58007Y355500D01*
X64000D01*
X70000Y349500D01*
X76151D01*
G02X76545Y349029I0J-400D01*
G03X76498Y348500I2955J-529D01*
G03X79500Y345498I3002J0D01*
G03X79634Y345501I0J3002D01*
G02X80045Y345031I17J-399D01*
G03X80031Y344945I2956J-525D01*
G02X79813Y344776I-198J30D01*
G03X79500Y344792I-310J-2986D01*
G03Y338788I0J-3002D01*
G01X79505D01*
G03X82500Y335998I2995J213D01*
G03X85502Y339000I0J3002D01*
G03X84467Y341268I-3002J0D01*
G02X84526Y341915I262J302D01*
G03X86002Y344500I-1526J2585D01*
G03X83000Y347502I-3002J0D01*
G03X82866Y347499I0J-3002D01*
G02X82455Y347969I-17J399D01*
G03X82502Y348500I-2955J529D01*
G03X82455Y349029I-3002J0D01*
G02X82849Y349500I394J71D01*
G01X82894D01*
G03X83000Y349498I110J3000D01*
G03X83106Y349500I-4J3002D01*
G01X93297D01*
G03X95100Y348898I1803J2399D01*
G03X95961Y349024I0J3002D01*
G02X96205Y348905I58J-192D01*
G03X99000Y346998I2795J1095D01*
G03X100448Y347370I1J3002D01*
G02X101038Y347068I193J-350D01*
G03X104019Y344423I2981J357D01*
G03X107021Y347425I0J3002D01*
G03X105590Y349983I-3002J0D01*
G03X106002Y351500I-2590J1518D01*
G03X103000Y354502I-3002J0D01*
G03X102029Y354341I-1J-3002D01*
G02X101500Y354719I-129J378D01*
G01Y357000D01*
X105626Y361126D01*
X105737Y361097D01*
G03X106500Y360998I765J2903D01*
G03X108250Y361561I0J3001D01*
G03X110000Y360998I1750J2438D01*
G03X113002Y364000I0J3002D01*
G03X111670Y366495I-3003J0D01*
G02X111610Y367110I223J332D01*
G01X116315Y371815D01*
G02X116998Y371529I283J-282D01*
G01Y371500D01*
G03X117561Y369750I3001J0D01*
G03Y366250I2438J-1750D01*
G03X116998Y364500I2438J-1750D01*
G03X123002I3002J0D01*
G03X122439Y366250I-3001J0D01*
G03Y369750I-2438J1750D01*
G03X123002Y371500I-2438J1750D01*
G03X122362Y373353I-3003J0D01*
G02X122676Y374000I314J247D01*
G01X129400D01*
G03X129529Y373795I2603J1495D01*
G02X129342Y373482I-164J-114D01*
G03X129000Y373502I-346J-2982D01*
G03X125998Y370500I0J-3002D01*
G03X127233Y368073I3002J0D01*
G02Y367427I-236J-323D01*
G03X125998Y365000I1767J-2427D01*
G03X132002I3002J0D01*
G03X130767Y367427I-3002J0D01*
G02Y368073I236J323D01*
G03X132002Y370500I-1767J2427D01*
G03X131650Y371910I-3002J0D01*
G02X132003Y372498I353J188D01*
G03X134600Y374000I-3J3002D01*
G01X135237D01*
G02X135602Y373437I0J-400D01*
G03X135348Y372250I2648J-1187D01*
G03X141152I2902J0D01*
G03X140898Y373437I-2902J0D01*
G02X141263Y374000I365J163D01*
G37*
G36*
G01X142500Y419500D02*
X156500D01*
X157800Y418200D01*
X157780Y418081D01*
X157778Y418074D01*
G03X157698Y417400I2822J-677D01*
G03X158406Y415501I2901J0D01*
G03X157548Y413400I2143J-2101D01*
G03X158092Y411677I3001J0D01*
G03X157580Y410000I2490J-1677D01*
G03X159849Y407089I3002J0D01*
G01X160000Y407051D01*
Y400000D01*
X158000Y398000D01*
X155277D01*
G02X154892Y398509I0J400D01*
G03X155002Y399300I-2792J791D01*
G03X149198I-2902J0D01*
G03X149308Y398509I2902J0D01*
G02X148923Y398000I-385J-109D01*
G01X141903D01*
G03X140100Y398602I-1803J-2399D01*
G03X139567Y398554I2J-3002D01*
G01X139464Y398536D01*
X138500Y399500D01*
Y415500D01*
X142500Y419500D01*
G37*
G36*
G01X170500Y92000D02*
X224000D01*
X231000Y85000D01*
Y74502D01*
G03X228169Y72500I0J-3003D01*
G01X226500D01*
X213500Y85500D01*
X209477D01*
G03X206123I-1677J-2490D01*
G01X204500D01*
X201500Y82500D01*
X174000D01*
X173837Y82337D01*
X173772Y82327D01*
G03X172508Y81692I327J-2227D01*
G01X160816Y70000D01*
X159652D01*
Y72600D01*
G03X159000Y74184I-2252J-1D01*
G01Y80500D01*
X170500Y92000D01*
G37*
G36*
G01X350605Y398949D02*
X360779D01*
X361743Y397985D01*
Y391557D01*
X350014Y379828D01*
X346060D01*
X342278Y383610D01*
X342287Y383704D01*
G03X342302Y384000I-2987J300D01*
G03X341664Y385850I-3001J0D01*
G03X342302Y387700I-2363J1850D01*
G03X339311Y390702I-3002J0D01*
G01Y395317D01*
X342943Y398949D01*
X344595D01*
X344598Y398752D01*
G03X350602I3002J48D01*
G01X350605Y398949D01*
G37*
%LPC*%
G75*
G36*
G01X41705Y335406D02*
X45705D01*
G02Y327904I0J-3751D01*
G01X41705D01*
G02Y335406I0J3751D01*
G37*
G36*
G01X125647Y320981D02*
G03X126000Y321393I-47J397D01*
G02X125998Y321500I3000J110D01*
G02X132002I3002J0D01*
G02X129353Y318519I-3002J0D01*
G03X129000Y318107I47J-397D01*
G02X129002Y318000I-3000J-110D01*
G02X122998I-3002J0D01*
G02X125647Y320981I3002J0D01*
G37*
G36*
G01X63442Y320072D02*
G03X62972Y320660I-341J210D01*
G02X62000Y320498I-973J2840D01*
G02Y326502I0J3002D01*
G02X64000Y325739I0J-3003D01*
G02X66000Y326502I2000J-2240D01*
G02X69002Y323500I0J-3002D01*
G02X68036Y321294I-3002J0D01*
G03Y320706I271J-294D01*
G02X69002Y318500I-2036J-2206D01*
G02X62998I-3002J0D01*
G02X63442Y320072I3002J1D01*
G37*
G36*
G01X139816Y322869D02*
G03X139984Y323531I-118J382D01*
G02X139128Y325630I2145J2099D01*
G02X145132I3002J0D01*
G02X143014Y322761I-3002J0D01*
G03X142846Y322099I118J-382D01*
G02X143702Y320000I-2145J-2099D01*
G02X137698I-3002J0D01*
G02X139816Y322869I3002J0D01*
G37*
G36*
G01X153477Y326627D02*
G02X153761Y327000I2523J-1627D01*
G02X152998Y329000I2240J2000D01*
G02X159002I3002J0D01*
G02X158239Y327000I-3003J0D01*
G02X159002Y325000I-2240J-2000D01*
G02X156000Y321998I-3002J0D01*
G02X154111Y322667I0J3001D01*
G03X153523Y322573I-252J-311D01*
G02X151000Y321198I-2523J1627D01*
G02Y327202I0J3002D01*
G02X152889Y326533I0J-3001D01*
G03X153477Y326627I252J311D01*
G37*
G36*
G01X143913Y336158D02*
G02X146000Y337002I2087J-2158D01*
G02Y330998I0J-3002D01*
G02X144003Y331758I-1J3002D01*
G02X141916Y330914I-2087J2158D01*
G02Y336918I0J3002D01*
G02X143913Y336158I1J-3002D01*
G37*
G36*
G01X94518Y341348D02*
G03X94362Y341567I-199J24D01*
G02X91998Y344500I637J2933D01*
G02X98002I3002J0D01*
G02X97982Y344152I-3002J-2D01*
G03X98138Y343933I199J-24D01*
G02X99500Y343239I-637J-2934D01*
G02X101500Y344002I2000J-2240D01*
G02Y337998I0J-3002D01*
G02X99500Y338761I0J3003D01*
G02X97500Y337998I-2000J2240D01*
G02X94498Y341000I0J3002D01*
G02X94518Y341348I3002J2D01*
G37*
G36*
G01X139789Y352031D02*
G03X139660Y352666I-294J271D01*
G02X137898Y355400I1240J2734D01*
G02X143902I3002J0D01*
G02X143111Y353369I-3003J0D01*
G03X143240Y352734I294J-271D01*
G02X145002Y350000I-1240J-2734D01*
G02X138998I-3002J0D01*
G02X139789Y352031I3003J0D01*
G37*
G36*
G01X76907Y327704D02*
G02X74998Y330500I1093J2796D01*
G02X78000Y333502I3002J0D01*
G02X80975Y330900I0J-3002D01*
G03X81557Y330599I396J53D01*
G02X82951Y330942I1393J-2659D01*
G02Y324938I0J-3002D01*
G02X82141Y325049I-1J3002D01*
G03X81633Y324644I-109J-385D01*
G02X81637Y324492I-2998J-155D01*
G02X75633I-3002J0D01*
G02X76982Y326998I3002J0D01*
G03X76907Y327704I-221J334D01*
G37*
G36*
G01X44516Y342294D02*
G02X44268Y343150I1353J856D01*
G02X45870Y341548I1602J0D01*
G02X45806Y341549I-7J1602D01*
G03X45452Y340936I-16J-400D01*
G02X45700Y340080I-1353J-856D01*
G02X44098Y341682I-1602J0D01*
G02X44162Y341681I7J-1602D01*
G03X44516Y342294I16J400D01*
G37*
G36*
G01X121427Y353767D02*
G03X122073I323J236D01*
G02X124500Y355002I2427J-1767D01*
G02X127488Y352291I0J-3002D01*
G03X128135Y352016I398J38D01*
G02X130000Y352666I1865J-2352D01*
G02Y346662I0J-3002D01*
G02X127012Y349373I0J3002D01*
G03X126365Y349648I-398J-38D01*
G02X126214Y349536I-1863J2354D01*
G03X126097Y349006I229J-328D01*
G02X126502Y347500I-2598J-1506D01*
G02X120498I-3002J0D01*
G02X120764Y348735I3002J0D01*
G03X120235Y349264I-365J164D01*
G02X119000Y348998I-1235J2736D01*
G02X116794Y349964I0J3002D01*
G03X116206I-294J-271D01*
G02X114000Y348998I-2206J2036D01*
G02Y355002I0J3002D01*
G02X116206Y354036I0J-3002D01*
G03X116794I294J271D01*
G02X119000Y355002I2206J-2036D01*
G02X121427Y353767I0J-3002D01*
G37*
G36*
G01X149643Y408505D02*
G03X149656Y409102I-260J304D01*
G02X148698Y411300I2044J2199D01*
G02X154702I3002J0D01*
G02X153590Y408968I-3001J0D01*
G03X153562Y408372I252J-311D01*
G02X154432Y406300I-2032J-2072D01*
G02X148628I-2902J0D01*
G02X149643Y408505I2903J0D01*
G37*
G54D22*
X61489Y332329D03*
X129500Y328000D03*
X113000Y344500D03*
X137000Y364000D03*
X95000Y321500D03*
X105410Y318500D03*
X95593Y333347D03*
X55000Y336000D03*
X72000Y335000D03*
X79000Y315500D03*
X35500Y327000D03*
X347000Y391200D03*
%LPD*%
G75*
G54D10*
X9000Y279000D03*
Y286000D03*
X19000Y262500D03*
X24200Y262508D03*
X28700D03*
X15000Y279000D03*
X18000Y314500D03*
X40500Y262000D03*
X33200Y262508D03*
X43000Y255500D03*
Y314500D03*
X33000D03*
X62500Y100500D03*
X54130Y152500D03*
X62000Y199500D03*
X54000Y213500D03*
X63000Y206000D03*
Y210500D03*
Y215000D03*
X48232Y264530D03*
X75500Y62000D03*
X76321Y78300D03*
X78500Y82250D03*
X73500Y112500D03*
X67000Y109000D03*
X69500Y130000D03*
X74000D03*
X75000Y141700D03*
X71400Y232900D03*
X71000Y330500D03*
X72000Y346300D03*
X93500Y125000D03*
X87000Y125500D03*
X93500Y130000D03*
X90500Y144500D03*
X95500Y145500D03*
X96500Y140000D03*
X91500D03*
X93900Y155200D03*
X95200Y151000D03*
X94500Y163000D03*
X98500Y159000D03*
X83500Y178000D03*
X97500Y172000D03*
X98500Y165500D03*
X92000Y173000D03*
X95500Y192000D03*
X83500Y193000D03*
Y188500D03*
X90500D03*
X94500Y197000D03*
X90500Y193500D03*
X97500Y214000D03*
X84500Y218000D03*
X95700Y227500D03*
X98500Y218500D03*
X96000Y241000D03*
X85700Y236500D03*
X96500Y235500D03*
X95900Y278900D03*
X99000Y175500D03*
Y188500D03*
Y197500D03*
Y206500D03*
Y201500D03*
X145000Y359000D03*
X140000Y401000D03*
X135100Y412600D03*
X143500Y418000D03*
X153270Y58400D03*
X151200Y75191D03*
X160500Y75500D03*
Y71500D03*
X156000Y320500D03*
Y316500D03*
X151500Y358000D03*
X158500Y405200D03*
X173170Y70840D03*
X182600Y289500D03*
X188900Y54960D03*
X208160Y73990D03*
X204770Y67780D03*
X207800Y83010D03*
X219200Y338800D03*
X219000Y348800D03*
X216500Y396000D03*
X223500Y58250D03*
X228500Y75500D03*
Y79000D03*
X238000Y345000D03*
X225500Y347500D03*
X230000D03*
X255400Y290100D03*
X307500Y160500D03*
X303500Y164000D03*
X297000Y310500D03*
X301000Y317000D03*
X293700Y317300D03*
X320500Y170000D03*
X312000Y269000D03*
Y256500D03*
Y264500D03*
X310500Y321000D03*
X312500Y307500D03*
X340500Y63500D03*
X338500Y259000D03*
X340500Y391600D03*
X349500Y61000D03*
X354500Y60920D03*
X344000Y103000D03*
X346000Y306500D03*
X351000Y308000D03*
X355000Y337000D03*
X347700Y381600D03*
X359800Y397700D03*
X348279Y405678D03*
X373500Y247000D03*
X375800Y255200D03*
X376500Y269000D03*
X365000Y268000D03*
X366000Y350850D03*
X369000Y413500D03*
X374500Y418500D03*
X384091Y200091D03*
X390000Y338500D03*
X381000Y365000D03*
X386500D03*
X389500Y370000D03*
X408500Y321998D03*
X410000Y338000D03*
X429442Y310075D03*
X413500Y373500D03*
X419000D03*
X420500Y381000D03*
X436500Y233000D03*
X435000Y250500D03*
X433000Y353500D03*
X463500Y92000D03*
X461000Y234500D03*
X457500Y227500D03*
Y223500D03*
X461000Y230000D03*
X448500Y250000D03*
X457500Y237400D03*
X453000Y250000D03*
X454000Y312500D03*
X448500Y311500D03*
X465500Y78500D03*
X479246Y178464D03*
X477500Y170500D03*
X481500Y193000D03*
X482000Y212500D03*
X468500Y264500D03*
X478500Y346000D03*
X493700Y79161D03*
X496000Y85000D03*
X497500Y148500D03*
X491500D03*
X496000Y163000D03*
X484000Y166000D03*
X485033Y174934D03*
X484000Y185500D03*
X483501Y346000D03*
X488500D03*
X504000Y64500D03*
X508500D03*
X513200Y66000D03*
X503950Y133500D03*
X503000Y155000D03*
X503500Y149000D03*
X501500Y192500D03*
X515500Y201000D03*
X513000Y210500D03*
X511500Y206500D03*
X513500Y215500D03*
X509000D03*
Y340500D03*
X504500D03*
X521500Y60000D03*
X529500Y60500D03*
X519500Y75500D03*
Y81500D03*
X524900Y99000D03*
X531000Y285500D03*
X518000Y382500D03*
X522100Y416500D03*
X541000Y96000D03*
X543520Y174970D03*
X539500Y292000D03*
X565400Y244700D03*
X567500Y403000D03*
X580000Y104800D03*
X576500Y98000D03*
X576000Y246500D03*
X583000Y297000D03*
X584000Y421900D03*
X592000Y141000D03*
Y163000D03*
Y151500D03*
Y173000D03*
X587500Y190000D03*
X602500Y183000D03*
X590650Y245680D03*
X602500Y404000D03*
X591000D03*
X597500Y421900D03*
X606902Y186000D03*
X614500Y398000D03*
Y403500D03*
X628500Y189500D03*
G54D20*
G01X387193Y143005D02*
X388112D01*
G02X388496Y142846I0J-543D01*
G02X388653Y142467I-379J-379D01*
G01Y141928D01*
G02X388118Y141390I-538J0D01*
G01X386720D01*
G03X385217Y140768I-1J-2125D01*
G01X383410Y138960D01*
G02X378980Y137125I-4430J4430D01*
G01X376053D01*
G02X375735Y137257I0J449D01*
G01X375592Y137400D01*
X375480D01*
G01X391130Y143005D02*
X389987D01*
G03X389436Y142615I0J-584D01*
G03X389425Y142582I549J-201D01*
G03X389403Y142421I562J-159D01*
G01Y141928D01*
G02X388120Y140640I-1288J0D01*
G01X386720D01*
G03X385748Y140237I1J-1375D01*
G01X383940Y138429D01*
G02X378981Y136375I-4960J4961D01*
G01X376053D01*
G03X375735Y136243I0J-449D01*
G01X375592Y136100D01*
X375480D01*
G01X395067Y146942D02*
X395929D01*
G02X396520Y146351I0J-591D01*
G01Y145891D01*
G02X396029Y145400I-491J0D01*
G01X394097D01*
G03X393190Y145351I-30J-7871D01*
G02X392305Y145300I-895J7820D01*
G01X385422D01*
G03X384974Y145261I5J-2653D01*
G01X384199Y145128D01*
G02X383879Y145100I-324J1860D01*
G01X377475D01*
G02X376880Y145276I0J1095D01*
G03X376543Y145375I-336J-521D01*
G01X399005Y146942D02*
X397861D01*
G03X397270Y146351I0J-591D01*
G01Y145891D01*
G02X396029Y144650I-1241J0D01*
G01X394099D01*
X394097Y144648D01*
X394095Y144650D01*
G03X393274Y144605I-21J-7121D01*
G02X392306Y144550I-972J8566D01*
G01X385422D01*
G03X385102Y144522I5J-1903D01*
G01X384326Y144388D01*
G02X383878Y144350I-446J2600D01*
G01X377474D01*
G02X377084Y144391I-3J1845D01*
G02X377075Y144350I-7J-20D01*
G01X376800Y144075D01*
X376688D01*
G01X387193Y150879D02*
X388337D01*
G03X388787Y151329I0J450D01*
G01Y151966D01*
G03X388213Y152540I-574J0D01*
G01X384075D01*
X383800Y152265D01*
X383688D01*
G01X391130Y150879D02*
X389987D01*
G02X389537Y151329I0J450D01*
G01Y151966D01*
G03X388213Y153290I-1324J0D01*
G01X384075D01*
X383800Y153565D01*
X383688D01*
G01X395067Y154816D02*
X396211D01*
G03X396661Y155266I0J450D01*
G01Y155903D01*
G03X396211Y156353I-450J0D01*
G01X393823D01*
G02X393599Y156371I0J1404D01*
G01X393154Y156443D01*
G03X392827Y156470I-332J-2028D01*
G01X386242D01*
G02X384069Y157370I0J3072D01*
G01X384068Y157369D01*
X383819Y157619D01*
Y157620D01*
G03X383204Y157875I-616J-617D01*
G01X380760D01*
G03X380758I-1J-1095D01*
G02X380019Y158031I2J1837D01*
G02X379828Y157600I-97J-215D01*
G01X399005Y154816D02*
X397861D01*
G02X397411Y155266I0J450D01*
G01Y155903D01*
G03X396211Y157103I-1200J0D01*
G01X393824D01*
G02X393732Y157110I3J653D01*
G01X393274Y157184D01*
G03X392826Y157220I-448J-2769D01*
G01X386242D01*
G02X384600Y157900I0J2322D01*
G01X384350Y158150D01*
G03X383203Y158625I-1147J-1147D01*
G01X380759D01*
G02X380322Y158718I3J1087D01*
G02X380168Y158801I437J995D01*
G03X379828Y158900I-336J-521D01*
G01X439446Y173465D02*
X439558D01*
X439701Y173608D01*
G02X440019Y173740I318J-317D01*
G01X440731D01*
G03X442975Y174670I0J3173D01*
G01X443995Y175690D01*
G03X444655Y177282I-1592J1593D01*
G01Y185861D01*
G02X445105Y186311I450J0D01*
G01X446248D01*
G01X442311D02*
X443455D01*
G02X443905Y185861I0J-450D01*
G01Y177283D01*
G02X443464Y176221I-1501J1D01*
G01X442444Y175201D01*
G02X440730Y174490I-1714J1712D01*
G01X440019D01*
G02X439701Y174622I0J449D01*
G01X439558Y174765D01*
X439446D01*
G54D11*
X26378Y340080D03*
X28150Y343150D03*
X40554Y340080D03*
X42326Y343150D03*
G54D21*
G01X384813Y165282D02*
X334967D01*
G03X326461Y161759I0J-12030D01*
G01X318124Y153422D01*
G02X317709Y153250I-415J414D01*
G01X277935D01*
G03X276308Y152576I0J-2301D01*
G01X236724Y112992D01*
G03X236050Y111365I1627J-1627D01*
G01Y72900D01*
G03X238075Y70875I2025J0D01*
G01X238889D01*
G02X239988Y70420I0J-1555D01*
G01X240508Y69900D01*
G01X384813Y164032D02*
X334967D01*
G03X327345Y160875I0J-10779D01*
G01X319009Y152539D01*
G02X317708Y152000I-1299J1297D01*
G01X277935D01*
G03X277192Y151692I0J-1050D01*
G01X237608Y112108D01*
G03X237300Y111365I742J-743D01*
G01Y85953D01*
G03X237610Y85643I310J0D01*
G02X238090Y85163I0J-480D01*
G01Y84283D01*
G02X237610Y83803I-480J0D01*
G03X237300Y83493I0J-310D01*
G01Y72900D01*
G03X238075Y72125I775J0D01*
G01X238889D01*
G03X239988Y72580I0J1555D01*
G01X240508Y73100D01*
G01X457330Y122167D02*
X456598Y121434D01*
G03X456355Y120849I585J-586D01*
G01Y119117D01*
G02X455817Y117817I-1836J-2D01*
G01X451200Y113200D01*
G02X450634Y112758I-2061J2055D01*
G02X448767Y112250I-1866J3172D01*
G01X413487D01*
G03X413044Y112124I-1J-837D01*
G03X412302Y111534I2195J-3522D01*
G01X410598Y109830D01*
G02X406785Y108250I-3814J3813D01*
G01X399181D01*
G02X394890Y110027I0J6069D01*
G01X393802Y111115D01*
G03X389856Y112750I-3946J-3944D01*
G01X367863D01*
G02X366236Y113424I0J2301D01*
G01X363008Y116652D01*
G03X362265Y116960I-743J-742D01*
G01X338752D01*
G03X337912Y116612I0J-1188D01*
G01X337500Y116200D01*
G01X454130Y122167D02*
X454862Y121435D01*
G02X455105Y120848I-587J-587D01*
G01Y119116D01*
G02X454933Y118701I-586J0D01*
G01X453556Y117324D01*
G02X453016I-270J270D01*
G01X453015Y117325D01*
G03X452475I-270J-270D01*
G01X451713Y116563D01*
G03Y116023I270J-270D01*
G01X451714Y116022D01*
G02Y115482I-270J-270D01*
G01X450316Y114084D01*
G02X449948Y113806I-1175J1173D01*
G02X448767Y113500I-1180J2123D01*
G01X413487D01*
G03X412383Y113186I-3J-2088D01*
G03X411418Y112418I2859J-4582D01*
G01X409714Y110714D01*
G02X406784Y109500I-2930J2929D01*
G01X399181D01*
G02X395774Y110911I0J4819D01*
G01X394686Y111999D01*
G03X389856Y114000I-4830J-4829D01*
G01X372276D01*
G02X371891Y114385I0J385D01*
G03X371506Y114770I-385J0D01*
G01X370436D01*
G03X370051Y114385I0J-385D01*
G02X369666Y114000I-385J0D01*
G01X367863D01*
G02X367120Y114308I0J1050D01*
G01X363892Y117536D01*
G03X362265Y118210I-1627J-1627D01*
G01X339485D01*
G02X338400Y118546I0J1920D01*
G02X338127Y118773I1085J1583D01*
G01X337500Y119400D01*
G01X473807Y135130D02*
X474711Y136034D01*
G02X475770Y136473I1059J-1058D01*
G01X476047D01*
G02X476790Y136165I0J-1050D01*
G01X477442Y135513D01*
G02X477750Y134770I-742J-743D01*
G01Y128685D01*
G02X477442Y127942I-1050J0D01*
G01X475894Y126394D01*
G02X475424I-235J235D01*
G03X474834I-295J-295D01*
G01X474122Y125682D01*
G03Y125092I295J-295D01*
G02Y124622I-235J-235D01*
G01X459081Y109581D01*
G02X458615Y109576I-236J235D01*
G03X457970Y109570I-319J-331D01*
G01X457320Y108920D01*
G03X457314Y108275I324J-326D01*
G02X457309Y107809I-240J-230D01*
G01X455500Y106000D01*
G02X450623Y103980I-4877J4876D01*
G01X388711D01*
G02X388385Y104115I0J461D01*
G01X386750Y105750D01*
G03X384335Y106750I-2415J-2416D01*
G01X374457D01*
G02X374052Y107155I0J405D01*
G03X373647Y107560I-405J0D01*
G01X372617D01*
G03X372212Y107155I0J-405D01*
G02X371807Y106750I-405J0D01*
G01X366185D01*
G02X365442Y107058I0J1050D01*
G01X360174Y112326D01*
G03X358547Y113000I-1627J-1627D01*
G01X344750D01*
G03X342774Y111024I0J-1976D01*
G01Y110119D01*
G02X342319Y109020I-1555J0D01*
G01X341799Y108500D01*
G01X473807Y139067D02*
X474549Y138325D01*
G03X476001Y137723I1453J1452D01*
G01X476047D01*
G02X477674Y137049I0J-2301D01*
G01X478326Y136397D01*
G02X479000Y134770I-1627J-1627D01*
G01Y128685D01*
G02X478326Y127058I-2301J0D01*
G01X456384Y105116D01*
G02X450622Y102730I-5760J5760D01*
G01X388711D01*
G02X387501Y103231I0J1711D01*
G01X385866Y104866D01*
G03X384335Y105500I-1531J-1532D01*
G01X366185D01*
G02X364558Y106174I0J2301D01*
G01X359290Y111442D01*
G03X358547Y111750I-743J-742D01*
G01X344750D01*
G03X344024Y111024I0J-726D01*
G01Y110121D01*
G03X344480Y109020I1557J0D01*
G01X344999Y108501D01*
Y108500D01*
G01X476798Y145650D02*
X479125D01*
G02X480363Y145137I0J-1750D01*
G01X486487Y139013D01*
G02X487000Y137775I-1237J-1238D01*
G01Y122567D01*
G02X485702Y119434I-4430J0D01*
G01X472259Y105991D01*
G02X448499Y96150I-23759J23759D01*
G01X359303D01*
G02X354657Y98075I0J6569D01*
G01X352952Y99780D01*
G02X352439Y101018I1237J1238D01*
G01Y103088D01*
G03X352263Y103807I-1555J0D01*
G03X351984Y104187I-1378J-720D01*
G01X351464Y104707D01*
G01X476798Y144400D02*
X479125D01*
G02X479479Y144253I0J-500D01*
G01X483133Y140599D01*
G02Y140183I-208J-208D01*
G03Y139767I208J-208D01*
G01X484019Y138881D01*
G03X484435I208J208D01*
G02X484851I208J-208D01*
G01X485603Y138129D01*
G02X485750Y137775I-353J-354D01*
G01Y122567D01*
G02X484818Y120318I-3180J0D01*
G01X484140Y119640D01*
G02X483626Y119546I-325J325D01*
G03X483112Y119451I-188J-420D01*
G01X482430Y118769D01*
G03X482335Y118255I325J-326D01*
G02X482241Y117741I-419J-189D01*
G01X473942Y109442D01*
G02X473482I-230J230D01*
G03X473022I-230J-230D01*
G01X472180Y108600D01*
G03Y108140I230J-230D01*
G02Y107680I-230J-230D01*
G01X471375Y106875D01*
G02X448500Y97400I-22875J22875D01*
G01X368426D01*
G02X368126Y97700I0J300D01*
G03X367826Y98000I-300J0D01*
G01X366586D01*
G03X366286Y97700I0J-300D01*
G02X365986Y97400I-300J0D01*
G01X359304D01*
G02X355541Y98959I-1J5319D01*
G01X353836Y100664D01*
G02X353689Y101018I353J354D01*
G01Y103086D01*
G02X354145Y104187I1557J0D01*
G01X354664Y104706D01*
Y104707D01*
G01X402800Y135000D02*
Y117974D01*
G02X402287Y116736I-1750J0D01*
G01X401650Y116099D01*
G01X404050Y135000D02*
Y117419D01*
G03X404418Y116531I1255J0D01*
G01X404850Y116099D01*
G01X437650Y116599D02*
G03X438550Y118772I-2173J2173D01*
G01Y123121D01*
G02X439253Y124819I2402J0D01*
G01X441147Y126715D01*
G03X441750Y128171I-1456J1456D01*
G01Y134313D01*
G01X440850Y116599D02*
X440402Y117048D01*
G02X439800Y118500I1450J1452D01*
G01Y119421D01*
G02X440200Y119821I400J0D01*
G03X440600Y120221I0J400D01*
G01Y121261D01*
G03X440200Y121661I-400J0D01*
G02X439800Y122061I0J400D01*
G01Y123121D01*
G02X440137Y123935I1152J0D01*
G01X442032Y125831D01*
G03X443000Y128171I-2342J2339D01*
G01Y129811D01*
G02X443560Y130371I560J0D01*
G03X444120Y130931I0J560D01*
G01Y131651D01*
G03X443560Y132211I-560J0D01*
G02X443000Y132771I0J560D01*
G01Y134313D01*
G01X457330Y122167D02*
X456528Y122969D01*
G02X456308Y123500I531J531D01*
G01Y124000D01*
G02X457858Y125550I1550J0D01*
G01X461640D01*
G03X464590Y128500I0J2950D01*
G01Y130733D01*
G02X465050Y131193I460J0D01*
G01X465933D01*
G01X454130Y122167D02*
X454772Y122808D01*
G03X455058Y123500I-692J691D01*
G01Y124000D01*
G02X457858Y126800I2800J0D01*
G01X461640D01*
G03X463340Y128500I0J1700D01*
G01Y130733D01*
G03X462880Y131193I-460J0D01*
G01X461996D01*
G54D12*
X46000Y82000D03*
X76100Y154400D03*
X75950Y164200D03*
X79500Y234500D03*
X73600Y252500D03*
X75500Y282500D03*
X63800Y274000D03*
X73500Y357500D03*
X70300D03*
X82500Y230500D03*
X98000Y420000D03*
X90000Y420500D03*
X85500D03*
X112880Y73020D03*
X110500Y382500D03*
X107300D03*
X126000Y67000D03*
Y62000D03*
X145900Y75200D03*
X142070Y77900D03*
X142000Y69535D03*
X152200Y416300D03*
X180390Y70720D03*
X191535Y41200D03*
X198135Y36500D03*
X254527Y33900D03*
X243500Y48650D03*
X252700Y44000D03*
X250222Y76300D03*
X247022D03*
X240508Y69900D03*
Y73100D03*
X269907Y76300D03*
X266707D03*
X285055D03*
X281855D03*
X298700Y327000D03*
Y323500D03*
X314763Y85237D03*
X312500Y87500D03*
X318000Y268500D03*
X310600Y335000D03*
X322200Y338500D03*
X341799Y108500D03*
X337500Y116200D03*
Y119400D03*
X344999Y108500D03*
X351464Y104707D03*
X354664D03*
X355000Y328000D03*
X365700Y92000D03*
X362500D03*
X365101Y191559D03*
Y188359D03*
X361124Y349876D03*
X375500Y350500D03*
X387193Y143005D03*
X391130D03*
X387193Y150879D03*
X391130D03*
Y209933D03*
X387193D03*
X388500Y391000D03*
X393500D03*
X388500Y400000D03*
X393500D03*
X401650Y116099D03*
X404850D03*
X395067Y146942D03*
X399005D03*
X395067Y154816D03*
X399005D03*
X402942Y150879D03*
X406879D03*
X402942Y166627D03*
X406879D03*
Y182374D03*
Y186311D03*
Y194185D03*
X395067Y186311D03*
Y190248D03*
X402942Y182374D03*
X399005Y198122D03*
X395067D03*
Y202059D03*
X402942Y205996D03*
X399005D03*
X406879Y202059D03*
X405463Y383000D03*
X410463D03*
X398500Y391000D03*
Y400000D03*
X426564Y186311D03*
Y190248D03*
X418690Y198122D03*
X422627Y186311D03*
Y182374D03*
X426564D03*
X414753Y190248D03*
X418690D03*
Y186311D03*
X414753D03*
X418690Y209933D03*
X421360Y359970D03*
X415463Y383000D03*
X437650Y116599D03*
X440850D03*
X446248Y143005D03*
X438374Y178437D03*
X446248Y182374D03*
Y186311D03*
X442311D03*
X434437Y190248D03*
Y194185D03*
X438374Y198122D03*
X442311Y190248D03*
Y194185D03*
X438374Y202059D03*
Y217807D03*
X434437D03*
X442500Y336089D03*
X439500Y341500D03*
X457330Y122167D03*
X454130D03*
X461996Y131193D03*
X450185Y143005D03*
X458059Y158753D03*
Y162690D03*
Y178437D03*
X454122Y166627D03*
Y178437D03*
X450185Y182374D03*
X454122D03*
X461996Y186311D03*
X458059Y182374D03*
X454122Y194185D03*
X450185D03*
X461996Y209933D03*
Y205996D03*
X450185D03*
X465933Y131193D03*
X473807Y135130D03*
Y139067D03*
Y146942D03*
X469870D03*
X465933Y154816D03*
Y158753D03*
Y194185D03*
X469870Y213870D03*
Y209933D03*
X465933Y202059D03*
X528500Y299000D03*
X545250Y256300D03*
X539977Y275124D03*
X537500Y296607D03*
X581400Y262100D03*
Y272100D03*
Y282100D03*
X581500Y302100D03*
X589953Y236600D03*
X619961Y224474D03*
Y227674D03*
G54D13*
G01X136000Y-65500D02*
Y-158000D01*
X506000D01*
Y-65500D01*
X136000D01*
G01X316000D02*
Y-158000D01*
G54D14*
G01X71400Y232900D02*
X74400Y235900D01*
Y251700D01*
X73600Y252500D01*
G01X238000Y345000D02*
X230400Y337400D01*
X224900D01*
X219000Y331500D01*
Y319500D01*
X180600Y281100D01*
X124500D01*
X104700Y261300D01*
Y249700D01*
X96000Y241000D01*
G01X182600Y289500D02*
X177800Y284700D01*
X123400D01*
X102200Y263500D01*
Y251500D01*
X87200Y236500D01*
X85700D01*
G01X216500Y396000D02*
Y401400D01*
X192900Y425000D01*
X143000D01*
X135000Y417000D01*
Y412700D01*
X135100Y412600D01*
G01X153270Y58400D02*
X156300D01*
X171600Y73700D01*
X184740D01*
X190390Y68050D01*
X204500D01*
X204770Y67780D01*
G01X151500Y358000D02*
X158500Y365000D01*
X172890D01*
X179890Y372000D01*
X272000D01*
X281000Y381000D01*
Y413000D01*
X298500Y430500D01*
X601000D01*
X607500Y424000D01*
Y420000D01*
X614500Y413000D01*
Y403500D01*
G01X219000Y348800D02*
Y339000D01*
X219200Y338800D01*
G01X340500Y63500D02*
Y61010D01*
X337000Y57510D01*
X314910D01*
X309700Y52300D01*
X289800D01*
X285000Y47500D01*
X250200D01*
X244600Y53100D01*
X228650D01*
X223500Y58250D01*
G01X301000Y317000D02*
X294000D01*
X293700Y317300D01*
G01X310500Y321000D02*
X313000D01*
X318000Y316000D01*
X333500D01*
X335250Y317750D01*
X341250D01*
X346000Y322500D01*
Y333500D01*
X358500Y346000D01*
X361150D01*
X366000Y350850D01*
G01X322200Y338500D02*
X314100D01*
X310600Y335000D01*
G01X355000Y328000D02*
X352000Y331000D01*
Y335500D01*
X353500Y337000D01*
X355000D01*
G01X373500Y247000D02*
Y252900D01*
X375800Y255200D01*
G01X463500Y92000D02*
X464170Y92670D01*
X470670D01*
X476500Y98500D01*
X493500D01*
X497500Y102500D01*
X506000D01*
X509500Y99000D01*
X524900D01*
G01X463500Y92000D02*
Y90500D01*
X467439Y86561D01*
Y84439D01*
X465500Y82500D01*
Y78500D01*
G01X503950Y133500D02*
Y133950D01*
X507500Y137500D01*
Y160000D01*
X501750Y165750D01*
X498560D01*
X496000Y163190D01*
Y163000D01*
G01X521500Y60000D02*
X524653Y56847D01*
X584506D01*
X587659Y60000D01*
X613500D01*
X650500Y97000D01*
Y178000D01*
X636250Y192250D01*
Y198014D01*
X635352Y198912D01*
Y204010D01*
X636150Y204808D01*
Y210850D01*
X633000Y214000D01*
Y242000D01*
X642000Y251000D01*
Y307000D01*
X638500Y310500D01*
X590000D01*
X579500Y321000D01*
Y351000D01*
X573500Y357000D01*
Y388500D01*
X579500Y394500D01*
X587500D01*
X597000Y404000D01*
X602500D01*
G01X529500Y60500D02*
X533500Y64500D01*
X544024D01*
X545774Y66250D01*
X550140D01*
X557043Y59347D01*
X567798D01*
X572451Y64000D01*
X573250D01*
X578750Y69500D01*
X618501D01*
X643500Y94499D01*
Y180501D01*
X630250Y193751D01*
Y243749D01*
X638819Y252318D01*
Y305682D01*
X637182Y307319D01*
X588182D01*
X573500Y322001D01*
Y351500D01*
X570950Y354050D01*
X566902D01*
X564500Y356452D01*
Y374000D01*
X561750Y376750D01*
Y381750D01*
X564750Y384750D01*
Y387640D01*
X567110Y390000D01*
X570604D01*
X578285Y397681D01*
X586181D01*
X591000Y402500D01*
Y404000D01*
G01X543520Y174970D02*
Y177980D01*
X533500Y188000D01*
Y207000D01*
X525100Y215400D01*
Y229500D01*
X536100Y240500D01*
X541000D01*
X545200Y244700D01*
X565400D01*
G01X518000Y382500D02*
Y393500D01*
X526250Y401750D01*
X537250D01*
X540500Y405000D01*
X565500D01*
X567500Y403000D01*
G01X584000Y421900D02*
X536900D01*
X531500Y416500D01*
X522100D01*
G01X584000Y421900D02*
X597500D01*
G01D02*
Y418500D01*
X609500Y406500D01*
Y403000D01*
X614500Y398000D01*
G54D15*
G01X385888Y187960D02*
X391830D01*
X393479Y186311D01*
X395067D01*
G01X402942Y182374D02*
X401442Y183874D01*
X385126D01*
G01X422627Y182374D02*
X421027Y180774D01*
X389056D01*
X387740Y182090D01*
G01X426564Y182374D02*
X424164Y179974D01*
X386810D01*
G01X414753Y186311D02*
X412954Y188110D01*
X407940D01*
X407339Y188711D01*
X394069D01*
X391780Y191000D01*
X389000D01*
G01X418690Y186311D02*
X416500Y188501D01*
Y190859D01*
X414811Y192548D01*
X394562D01*
X393110Y194000D01*
X390500D01*
G01X406879Y194185D02*
X405379Y195685D01*
X390814D01*
G01X391000Y197500D02*
X391878Y196622D01*
X407798D01*
X408430Y195990D01*
X415550D01*
X416500Y195040D01*
Y192438D01*
X418690Y190248D01*
G01X393210Y200220D02*
X396907D01*
X399005Y198122D01*
G01X406879Y182374D02*
X404579Y184674D01*
X385826D01*
X385000Y185500D01*
X383500D01*
G01X386500Y189500D02*
X391799D01*
X393388Y187911D01*
X405279D01*
X406879Y186311D01*
G01X390000Y193000D02*
X392879D01*
X394131Y191748D01*
X413253D01*
X414753Y190248D01*
G01X458059Y158753D02*
X459882Y156930D01*
X466860D01*
X468130Y158200D01*
X477400D01*
G01X446248Y182374D02*
X448585Y184711D01*
X462990D01*
X464000Y185721D01*
Y186871D01*
G01X465154Y184654D02*
X464411Y183911D01*
X451722D01*
X450185Y182374D01*
G54D16*
G01X145964Y-110118D02*
G03I-634J0D01*
G01X149695D02*
G03I-1038J0D01*
G01X168013Y-137456D02*
G03I-634J0D01*
G01X155900Y-133655D02*
G03I-632J0D01*
G01X161735Y-128639D02*
G03I-1458J0D01*
G01X158530Y-131428D02*
G03I-1041J0D01*
G01X158461Y-119126D02*
G03I-1283J0D01*
G01X162690Y-117490D02*
G03I-1584J0D01*
G01X169809Y-121292D02*
G03I-2180J0D01*
G01X165531Y-125255D02*
G03I-1869J0D01*
G01X167813Y-115513D02*
G03I-1971J0D01*
G01X154775Y-120500D02*
G03I-892J0D01*
G01X162681Y-102774D02*
G03I-1584J0D01*
G01X158451Y-101149D02*
G03I-1283J0D01*
G01X159258Y-110118D02*
G03I-1868J0D01*
G01X169812Y-98951D02*
G03I-2180J0D01*
G01X167802Y-104739D02*
G03I-1971J0D01*
G01X165183Y-110118D02*
G03I-2180J0D01*
G01X171881D02*
G03I-2642J0D01*
G01X152135Y-98681D02*
G03I-632J0D01*
G01X154064Y-110118D02*
G03I-1460J0D01*
G01X154764Y-99775D02*
G03I-892J0D01*
G01X158530Y-88809D02*
G03I-1041J0D01*
G01X161742Y-91601D02*
G03I-1458J0D01*
G01X165531Y-94981D02*
G03I-1869J0D01*
G01X171080Y-131739D02*
G03I-1282J0D01*
G01X169322Y-135033D02*
G03I-892J0D01*
G01X180669Y-131528D02*
G03I-1870J0D01*
G01X180255Y-136311D02*
G03I-1456J0D01*
G01X179841Y-140261D02*
G03I-1042J0D01*
G01X179433Y-143587D02*
G03I-634J0D01*
G01X181439Y-119680D02*
G03I-2640J0D01*
G01X175373Y-123081D02*
G03I-1968J0D01*
G01X173018Y-127816D02*
G03I-1584J0D01*
G01X174681Y-116876D02*
G03I-2640J0D01*
G01X180979Y-125917D02*
G03I-2180J0D01*
G01X186177Y-123075D02*
G03I-1971J0D01*
G01X188199Y-116876D02*
G03I-2640J0D01*
G01X175452Y-97124D02*
G03I-1968J0D01*
G01X186225Y-97178D02*
G03I-1971J0D01*
G01X181439Y-100556D02*
G03I-2640J0D01*
G01X174681Y-103361D02*
G03I-2640J0D01*
G01X188199D02*
G03I-2640J0D01*
G01X179841Y-79975D02*
G03I-1042J0D01*
G01X171217Y-88444D02*
G03I-1282J0D01*
G01X173123Y-92378D02*
G03I-1584J0D01*
G01X180255Y-83924D02*
G03I-1456J0D01*
G01X180669Y-88708D02*
G03I-1870J0D01*
G01X180979Y-94320D02*
G03I-2180J0D01*
G01X179433Y-76648D02*
G03I-634J0D01*
G01X191096Y-134658D02*
G03I-892J0D01*
G01X192135Y-136781D02*
G03I-631J0D01*
G01X198775Y-128635D02*
G03I-1458J0D01*
G01X195808Y-125255D02*
G03I-1869J0D01*
G01X200547Y-113952D02*
G03X203345Y-117196I7247J3422D01*
G01X192148Y-121285D02*
G03I-2180J0D01*
G01X187928Y-127802D02*
G03I-1584J0D01*
G01X189667Y-131511D02*
G03I-1283J0D01*
G01X200699Y-105836D02*
G03X200547Y-113953I8974J-4228D01*
G01X208284Y-101612D02*
G03X200698Y-105835I-219J-8531D01*
G01X192148Y-98951D02*
G03I-2180J0D01*
G01X191108Y-82727D02*
G03I-634J0D01*
G01X190184Y-85250D02*
G03I-893J0D01*
G01X195808Y-94981D02*
G03I-1869J0D01*
G01X187839Y-92457D02*
G03I-1584J0D01*
G01X189190Y-88538D02*
G03I-1283J0D01*
G01X214259Y-115661D02*
G03X213314Y-114453I-714J415D01*
G01X202049Y-108260D02*
G03X205722Y-116181I7039J-1548D01*
G01X218075Y-112869D02*
G03X219083Y-115752I4343J-99D01*
G01X208854Y-116658D02*
G03X213313Y-114452I-2485J10632D01*
G01X208470Y-118462D02*
G03X214261Y-115663I-1122J9711D01*
G01X203346Y-117195D02*
G03X208470Y-118461I4545J7394D01*
G01X205721Y-116179D02*
G03X208853Y-116659I2561J6250D01*
G01X215903Y-114020D02*
G03X219079Y-118061I6190J1597D01*
G01X215904Y-114020D02*
Y-111835D01*
G01X227413Y-112869D02*
X218074D01*
G01X214175Y-103951D02*
G03X208283Y-101613I-6403J-7542D01*
G01X213150Y-105147D02*
G03X214175Y-103951I410J686D01*
G01X213152Y-105146D02*
G03X208030Y-103430I-5122J-6786D01*
G01X208029Y-103429D02*
G03X202049Y-108259I-48J-6058D01*
G01X225189Y-111399D02*
G03X218071I-3559J159D01*
G01X218070Y-111418D02*
Y-111399D01*
G01X225188Y-111418D02*
X218070D01*
G01X227412Y-111835D02*
G03X215906I-5753J223D01*
G01X230059Y-117625D02*
Y-102034D01*
G01X230060Y-117626D02*
G03X232080I1010J239D01*
G01X226590Y-116472D02*
G03X225311Y-115210I-817J451D01*
G01X234673Y-114020D02*
G03X237849Y-118061I6190J1597D01*
G01X232081Y-102041D02*
Y-117625D01*
G01X219083Y-115753D02*
G03X225311Y-115211I2844J3371D01*
G01X219079Y-118060D02*
G03X226591Y-116473I2662J5972D01*
G01X227413Y-111835D02*
Y-112869D01*
G01X232080Y-102041D02*
G03X230060Y-102034I-1011J-236D01*
G01X225188Y-111399D02*
Y-111418D01*
G01X234675Y-114020D02*
Y-111835D01*
G01X246181D02*
G03X234675I-5753J223D01*
G01X252849Y-116771D02*
G03X254892Y-115895I-74J2994D01*
G01X236844Y-112869D02*
G03X237852Y-115752I4343J-99D01*
G01X237848Y-118060D02*
G03X245360Y-116473I2662J5972D01*
G01X245358Y-116472D02*
G03X244079Y-115210I-817J451D01*
G01X237852Y-115753D02*
G03X244080Y-115211I2844J3371D01*
G01X249566Y-115529D02*
G03X252307Y-116760I2985J2980D01*
G01Y-116761D02*
G03X252849Y-116772I366J4691D01*
G01X250282Y-118087D02*
G03X254318Y-118340I2605J9244D01*
G01X247897Y-116444D02*
G03X250283Y-118086I3752J2898D01*
G01X249568Y-115529D02*
G03X247898Y-116443I-748J-616D01*
G01X255608Y-108618D02*
G03X253612Y-107689I-3116J-4086D01*
G01X246181Y-111835D02*
Y-112869D01*
G01D02*
X236844D01*
G01X255002Y-114328D02*
G03X252723Y-112986I-3540J-3405D01*
G01X249955Y-112030D02*
G03X252723Y-112985I8208J19302D01*
G01X243957Y-111399D02*
Y-111418D01*
G01X243958Y-111399D02*
G03X236840I-3559J159D01*
G01X236841Y-111418D02*
Y-111399D01*
G01X243957Y-111418D02*
X236841D01*
G01X248537Y-109748D02*
G03X249956Y-112031I2652J66D01*
G01X248537Y-108250D02*
Y-109748D01*
G01X250179Y-106359D02*
G03X248537Y-108249I2747J-4045D01*
G01X256884Y-107368D02*
G03X250178Y-106359I-4153J-4811D01*
G01X253611Y-107689D02*
G03X251080Y-107949I-869J-3992D01*
G01X251081Y-107948D02*
G03X250837Y-110104I805J-1183D01*
G01Y-110106D02*
G03X254306Y-111513I5270J8013D01*
G01X260954Y-116041D02*
Y-107954D01*
G01X254892Y-115895D02*
G03X255001Y-114328I-764J840D01*
G01X269619Y-117484D02*
Y-106797D01*
G01X269620Y-117484D02*
G03X271926I1153J198D01*
G01X266864Y-117375D02*
G03X266002Y-116329I-764J249D01*
G01X262978Y-115462D02*
G03X266002Y-116329I2046J1428D01*
G01X260955Y-116043D02*
G03X264164Y-118351I2956J725D01*
G01X265463Y-118350D02*
X264165D01*
G01X265464Y-118352D02*
G03X266864Y-117374I-24J1525D01*
G01X256906Y-116470D02*
G03X257054Y-113728I-3143J1545D01*
G01X254317Y-118340D02*
G03X256906Y-116470I-1259J4470D01*
G01X262978Y-107954D02*
Y-115463D01*
G01X257054Y-113729D02*
G03X254307Y-111513I-3470J-1490D01*
G01X271969Y-102342D02*
G03I-1194J0D01*
G01X271926Y-106797D02*
G03X269620I-1153J-409D01*
G01X266003Y-107954D02*
X262978D01*
G01X266004Y-107955D02*
G03X266008Y-105932I-177J1012D01*
G01X262978D02*
X266008D01*
G01X262971Y-103419D02*
X262978Y-105932D01*
G01X262972Y-103418D02*
G03X260954Y-103491I-1005J-141D01*
G01Y-105932D02*
Y-103492D01*
G01X259930Y-105932D02*
X260954D01*
G01X259930D02*
G03X259981Y-107955I298J-1005D01*
G01X260954Y-107954D02*
X259982D01*
G01X255606Y-108620D02*
G03X256885Y-107367I599J667D01*
G01X290671Y-110842D02*
G03X290703Y-118351I860J-3751D01*
G01X276837Y-114305D02*
G03X278891Y-116297I4069J2141D01*
G01X274529Y-113568D02*
G03X275888Y-116443I5718J944D01*
G01X275887D02*
G03X279572Y-118352I4392J3967D01*
G01X281425Y-118350D02*
X279571D01*
G01X281425D02*
G03X284525Y-117161I0J4636D01*
G01X285201Y-116508D02*
X284524Y-117161D01*
G01X285201Y-116508D02*
G03X283966Y-115211I-695J574D01*
G01X281510Y-116675D02*
G03X283966Y-115212I-989J4453D01*
G01X278889Y-116297D02*
G03X281508Y-116677I1946J4197D01*
G01X271926Y-106797D02*
Y-117484D01*
G01X274529Y-113566D02*
Y-111839D01*
G01X276446Y-112943D02*
G03X276837Y-114305I4162J458D01*
G01X276445Y-112066D02*
Y-112943D01*
G01X283833Y-109274D02*
G03X285403Y-108106I585J852D01*
G01X285402D02*
G03X280919Y-105777I-4776J-3714D01*
G01X279541D02*
X280919D01*
G01X279540D02*
G03X274999Y-109274I1260J-6333D01*
G01X274998D02*
G03X274529Y-111839I9988J-3152D01*
G01X276849Y-109932D02*
G03X276446Y-112066I5467J-2137D01*
G01X280036Y-107542D02*
G03X276849Y-109933I664J-4205D01*
G01X282662Y-108199D02*
G03X280037Y-107539I-2313J-3650D01*
G01X283833Y-109275D02*
G03X282662Y-108202I-9277J-8949D01*
G01X294457Y-116619D02*
G03Y-112289I-51J2165D01*
G01X291853Y-116620D02*
X294456D01*
G01X291853Y-112289D02*
G03Y-116619I195J-2165D01*
G01X294165Y-118350D02*
X290701D01*
G01X294165D02*
G03X296471Y-117226I-1088J5161D01*
G01X296473Y-117625D02*
Y-117226D01*
G01X296474Y-117627D02*
G03X298494I1010J185D01*
G01X298495Y-109394D02*
Y-117625D01*
G01X301067Y-108534D02*
Y-106508D01*
G01X301615Y-108534D02*
X301067D01*
G01X301615Y-106508D02*
Y-108534D01*
G01X302461Y-106508D02*
X301615D01*
G01X302461Y-106001D02*
Y-106508D01*
G01X300223Y-106001D02*
X302461D01*
G01X300223Y-106508D02*
Y-106001D01*
G01X301067Y-106508D02*
X300223D01*
G01X305164Y-106001D02*
X304731D01*
G01X305713Y-108544D02*
X305164Y-106001D01*
G01X305171Y-108544D02*
X305713D01*
G01X304889Y-106871D02*
X305171Y-108544D01*
G01X304309D02*
X304889Y-106871D01*
G01X304086Y-108544D02*
X304309D01*
G01X303501Y-106887D02*
X304086Y-108544D01*
G01X303226D02*
X303501Y-106887D01*
G01X302698Y-108544D02*
X303226D01*
G01X303243Y-106001D02*
X302698Y-108544D01*
G01X303648Y-106001D02*
X303243D01*
G01X304192Y-107632D02*
X303648Y-106001D01*
G01X304731D02*
X304192Y-107632D01*
G01X294456Y-112288D02*
X291853D01*
G01X296473Y-110841D02*
Y-109686D01*
G01X296472Y-110841D02*
G03X292878Y-110536I-3256J-17043D01*
G01X292879Y-110535D02*
G03X290670Y-110842I280J-10112D01*
G01X298496Y-109394D02*
G03X295031Y-105933I-3962J-501D01*
G01X291563Y-105932D02*
X295031D01*
G01X291562D02*
G03X289112Y-107085I584J-4421D01*
G01Y-107086D02*
G03X289820Y-108520I585J-603D01*
G01X290987Y-107954D02*
G03X289821Y-108520I1446J-4464D01*
G01X294740Y-107954D02*
X290987D01*
G01X296473Y-109686D02*
G03X294742Y-107955I-1598J133D01*
G01X381000Y-125000D02*
Y-133000D01*
X385000D01*
G01X391000Y-125000D02*
X390200Y-125267D01*
X389600Y-125933D01*
X389200Y-126733D01*
X388900Y-127800D01*
X388800Y-129000D01*
X388900Y-130200D01*
X389200Y-131267D01*
X389600Y-132067D01*
X390200Y-132733D01*
X391000Y-133000D01*
X391800Y-132733D01*
X392400Y-132067D01*
X392800Y-131267D01*
X393100Y-130200D01*
X393200Y-129000D01*
X393100Y-127800D01*
X392800Y-126733D01*
X392400Y-125933D01*
X391800Y-125267D01*
X391000Y-125000D01*
G01X399000Y-133000D02*
X399700Y-132867D01*
X400500Y-132467D01*
X401000Y-131800D01*
X401200Y-130867D01*
X401000Y-129934D01*
X400400Y-129133D01*
X399500Y-128733D01*
X398500D01*
X397900Y-128467D01*
X397400Y-127800D01*
X397200Y-126867D01*
X397500Y-125933D01*
X398200Y-125267D01*
X399000Y-125000D01*
X399800Y-125267D01*
X400500Y-125933D01*
X400800Y-126867D01*
X400600Y-127800D01*
X400100Y-128467D01*
X399500Y-128733D01*
X398500D01*
X397600Y-129133D01*
X397000Y-129934D01*
X396800Y-130867D01*
X397000Y-131800D01*
X397500Y-132467D01*
X398300Y-132867D01*
X399000Y-133000D01*
G01X404000Y-135667D02*
X410000D01*
G01X412900Y-131934D02*
X413700Y-132600D01*
X414600Y-133000D01*
X415400D01*
X416200Y-132600D01*
X416800Y-131934D01*
X417100Y-131000D01*
X416900Y-130067D01*
X416400Y-129267D01*
X415500Y-128733D01*
X414300Y-128467D01*
X413600Y-127933D01*
X413300Y-127000D01*
X413500Y-126067D01*
X414000Y-125400D01*
X414700Y-125000D01*
X415400D01*
X416100Y-125267D01*
X416700Y-125933D01*
G01X421800Y-125000D02*
X424200D01*
G01X423000D02*
Y-133000D01*
G01X421800D02*
X424200D01*
G01X431600Y-129000D02*
X433600D01*
Y-131400D01*
X433000Y-132200D01*
X432300Y-132733D01*
X431300Y-133000D01*
X430300Y-132733D01*
X429600Y-132200D01*
X429000Y-131400D01*
X428600Y-130467D01*
X428400Y-129400D01*
Y-128467D01*
X428600Y-127667D01*
X429000Y-126733D01*
X429600Y-125933D01*
X430200Y-125400D01*
X431000Y-125000D01*
X431700D01*
X432500Y-125267D01*
X433100Y-125800D01*
G01X437100Y-126333D02*
X437700Y-125533D01*
X438400Y-125133D01*
X439200Y-125000D01*
X440200Y-125267D01*
X440900Y-125933D01*
X441100Y-126733D01*
X441000Y-127534D01*
X440600Y-128200D01*
X438600Y-129533D01*
X437700Y-130467D01*
X437100Y-131800D01*
X436900Y-133000D01*
X441100D01*
G54D17*
G01X98000Y420000D02*
X88500Y429500D01*
X59880D01*
X50300Y419920D01*
Y371800D01*
X36000Y357500D01*
X12500D01*
X6500Y351500D01*
Y281500D01*
X9000Y279000D01*
G01X90000Y420500D02*
X82500Y428000D01*
X61139D01*
X51800Y418661D01*
Y370300D01*
X37000Y355500D01*
X13000D01*
X8000Y350500D01*
Y287000D01*
X9000Y286000D01*
G01X85500Y420500D02*
X79500Y426500D01*
X62760D01*
X53300Y417040D01*
Y369300D01*
X37500Y353500D01*
X13500D01*
X9500Y349500D01*
Y289000D01*
X11500Y287000D01*
Y282500D01*
X15000Y279000D01*
G01X398500Y400000D02*
X394500Y404000D01*
X386879D01*
X367000Y384121D01*
Y378821D01*
X352179Y364000D01*
X330000D01*
X326500Y360500D01*
X229244D01*
X225744Y364000D01*
X202000D01*
X185000Y347000D01*
Y326117D01*
X157733Y298850D01*
X154949D01*
X152199Y301600D01*
X130400D01*
X128100Y299300D01*
X115821D01*
X114021Y297500D01*
X99890D01*
X95640Y301750D01*
X93360D01*
X93010Y301400D01*
X92912D01*
X89762Y298250D01*
X86360D01*
X83610Y295500D01*
X76500D01*
X74500Y293500D01*
X65490D01*
X64740Y294250D01*
X59567D01*
X32317Y267000D01*
X24500D01*
X20008Y262508D01*
X19008D01*
X19000Y262500D01*
G01X63000Y206000D02*
X60500Y208500D01*
Y214500D01*
X59000Y216000D01*
X55000D01*
X54500Y216500D01*
Y220500D01*
X52500Y222500D01*
X42500D01*
X35500Y229500D01*
Y254879D01*
X30379Y260000D01*
X26708D01*
X24200Y262508D01*
G01X415463Y383000D02*
X411463Y379000D01*
X403000D01*
X400500Y381500D01*
Y387000D01*
X402000Y388500D01*
Y401000D01*
X397000Y406000D01*
X386757D01*
X365500Y384743D01*
Y379443D01*
X351557Y365500D01*
X324317D01*
X320883Y362066D01*
X231934D01*
X228000Y366000D01*
X201500D01*
X183000Y347500D01*
Y326500D01*
X160300Y303800D01*
X142305D01*
X141655Y303150D01*
X129472D01*
X127322Y301000D01*
X115399D01*
X113399Y299000D01*
X101500D01*
X96500Y304000D01*
X93390D01*
X89640Y300250D01*
X84249D01*
X80999Y297000D01*
X67433D01*
X65433Y299000D01*
X35000D01*
X28000Y306000D01*
X24000D01*
X18000Y312000D01*
Y314500D01*
G01X63000Y215000D02*
X59750Y218250D01*
Y219433D01*
X57683Y221500D01*
X56000D01*
X44500Y233000D01*
Y248001D01*
X29993Y262508D01*
X28700D01*
G01X388500Y400000D02*
X387500D01*
X370500Y383000D01*
Y377744D01*
X349756Y357000D01*
X228500D01*
X226000Y359500D01*
X203500D01*
X192500Y348500D01*
Y317122D01*
X171878Y296500D01*
X161283D01*
X157533Y292750D01*
X143445D01*
X141445Y294750D01*
X139445D01*
X137895Y296300D01*
X117065D01*
X115265Y294500D01*
X92521D01*
X89123Y291102D01*
X84287D01*
X82335Y289150D01*
X72284D01*
X69884Y286750D01*
X65487D01*
X59237Y280500D01*
X51500D01*
X39000Y268000D01*
Y263500D01*
X40500Y262000D01*
G01X33200Y262508D02*
Y264200D01*
X37500Y268500D01*
Y268622D01*
X50878Y282000D01*
X58615D01*
X64865Y288250D01*
X69262D01*
X71662Y290650D01*
X73967D01*
X77067Y293750D01*
X78933D01*
X79933Y292750D01*
X88649D01*
X91899Y296000D01*
X114643D01*
X116443Y297800D01*
X138517D01*
X140067Y296250D01*
X142067D01*
X144067Y294250D01*
X145933D01*
X146883Y295200D01*
X149005D01*
X151155Y297350D01*
X159166D01*
X162616Y300800D01*
X167801D01*
X169001Y302000D01*
X174500D01*
X186500Y314000D01*
Y345708D01*
X202792Y362000D01*
X225622D01*
X229122Y358500D01*
X348801D01*
X368500Y378199D01*
Y383499D01*
X387501Y402500D01*
X391000D01*
X393500Y400000D01*
G01X43000Y255500D02*
X46000Y252500D01*
Y234000D01*
X57000Y223000D01*
X58305D01*
X65500Y215805D01*
Y213000D01*
X63000Y210500D01*
G01X410463Y383000D02*
X407963Y380500D01*
X404000D01*
X403000Y381500D01*
Y386500D01*
X404474Y387974D01*
Y402025D01*
X398999Y407500D01*
X386135D01*
X363500Y384865D01*
Y379565D01*
X350935Y367000D01*
X323695D01*
X320261Y363566D01*
X234933D01*
X230499Y368000D01*
X201000D01*
X181000Y348000D01*
Y327000D01*
X159400Y305400D01*
X141783D01*
X141033Y304650D01*
X128850D01*
X126700Y302500D01*
X115183D01*
X109933Y307750D01*
X89250D01*
X80000Y298500D01*
X68055D01*
X66055Y300500D01*
X42000D01*
X37250Y305250D01*
Y310250D01*
X33000Y314500D01*
G01X43000D02*
X55500Y302000D01*
X66610D01*
X68610Y304000D01*
X83378D01*
X88628Y309250D01*
X147550D01*
X149700Y307100D01*
X158100D01*
X170000Y319000D01*
Y323500D01*
X179000Y332500D01*
Y348500D01*
X200000Y369500D01*
X233000D01*
X237434Y365066D01*
X319639D01*
X323073Y368500D01*
X350313D01*
X362000Y380187D01*
Y385487D01*
X385513Y409000D01*
X399998D01*
X406241Y402757D01*
Y383778D01*
X405463Y383000D01*
G01X46000Y82000D02*
X47300Y80700D01*
Y75683D01*
X49522Y73461D01*
Y72667D01*
X50839Y71350D01*
X51633D01*
X63983Y59000D01*
X85990D01*
X89050Y62060D01*
X118940D01*
X124000Y57000D01*
X145501D01*
X148501Y60000D01*
X151500D01*
X153400Y61900D01*
X155900D01*
X174100Y80100D01*
X204890D01*
X207800Y83010D01*
G01X62500Y100500D02*
X64500Y102500D01*
Y105501D01*
X60500Y109501D01*
Y114500D01*
X55990Y119010D01*
Y126933D01*
X55500Y127423D01*
Y133000D01*
X50500Y138000D01*
Y148870D01*
X54130Y152500D01*
G01X48232Y264530D02*
X52000Y260762D01*
Y253000D01*
X56450Y248550D01*
Y245500D01*
X59000Y242950D01*
Y228890D01*
X60250Y227640D01*
Y223884D01*
X67500Y216634D01*
Y207000D01*
X63000Y202500D01*
X60000D01*
X59000Y201500D01*
Y186001D01*
X68500Y176501D01*
Y152471D01*
X61000Y144971D01*
Y127000D01*
X63500Y124500D01*
X67000D01*
X70500Y121000D01*
Y115500D01*
X73500Y112500D01*
G01X54000Y213500D02*
Y213000D01*
X53600Y212600D01*
Y204900D01*
X56400Y202100D01*
Y178600D01*
X61000Y174000D01*
Y169207D01*
X64000Y166207D01*
Y150800D01*
X59000Y145800D01*
Y125500D01*
X65250Y119250D01*
Y110750D01*
X67000Y109000D01*
G01X75000Y141700D02*
X70500Y146200D01*
Y178000D01*
X62000Y186500D01*
Y199500D01*
G01X398500Y391000D02*
X394850Y394650D01*
X384406D01*
X372500Y382744D01*
Y377622D01*
X349999Y355121D01*
X224257D01*
X221878Y357500D01*
X204000D01*
X198500Y352000D01*
Y331917D01*
X194000Y327417D01*
Y316000D01*
X169250Y291250D01*
X142823D01*
X140823Y293250D01*
X138823D01*
X137273Y294800D01*
X120700D01*
X118600Y292700D01*
X100200D01*
X96100Y288600D01*
X87693D01*
X86691Y289602D01*
X84909D01*
X82957Y287650D01*
X72906D01*
X70506Y285250D01*
X66109D01*
X64850Y283991D01*
Y283973D01*
X57820Y276943D01*
Y256058D01*
X59500Y254378D01*
Y250682D01*
X61000Y249182D01*
Y229719D01*
X62250Y228469D01*
Y224750D01*
X76843Y210157D01*
Y184657D01*
X83500Y178000D01*
G01Y188500D02*
X78863Y193137D01*
Y219000D01*
X67863Y230000D01*
X63500D01*
X62500Y231000D01*
Y250010D01*
X61950Y250560D01*
Y254050D01*
X59320Y256680D01*
Y276321D01*
X61499Y278500D01*
X65878D01*
X73528Y286150D01*
X77013D01*
X78413Y284750D01*
X96994D01*
X99844Y287600D01*
X118701D01*
X119301Y288200D01*
X168577D01*
X195500Y315123D01*
Y326709D01*
X200000Y331209D01*
Y335105D01*
X202750Y337855D01*
Y339733D01*
X204567Y341550D01*
X206445D01*
X218516Y353621D01*
X350621D01*
X374500Y377500D01*
Y382622D01*
X385028Y393150D01*
X391350D01*
X393500Y391000D01*
G01X83500Y193000D02*
X80500Y196000D01*
Y220000D01*
X69000Y231500D01*
X67000D01*
X64000Y234500D01*
Y242500D01*
X67450Y245950D01*
Y252840D01*
X65840Y254450D01*
X64549D01*
X61180Y257819D01*
Y275680D01*
X62000Y276500D01*
X66000D01*
X74150Y284650D01*
X76391D01*
X77791Y283250D01*
X97616D01*
X100466Y286100D01*
X119599D01*
X120199Y286700D01*
X169199D01*
X174849Y292350D01*
X186849D01*
X204500Y310001D01*
Y333001D01*
X208000Y336501D01*
Y340983D01*
X219138Y352121D01*
X351621D01*
X377250Y377750D01*
Y382250D01*
X386000Y391000D01*
X388500D01*
G01X76321Y78300D02*
Y75008D01*
X78829Y72500D01*
X86872D01*
X87372Y73000D01*
Y73470D01*
X87872Y73970D01*
X89372D01*
X89872Y73470D01*
Y73000D01*
X90372Y72500D01*
X91872D01*
X92372Y73000D01*
Y75010D01*
X92872Y75510D01*
X94372D01*
X94872Y75010D01*
Y73000D01*
X95372Y72500D01*
X96872D01*
X97372Y73000D01*
Y75010D01*
X97872Y75510D01*
X99372D01*
X99872Y75010D01*
Y73000D01*
X100372Y72500D01*
X110359D01*
X111989Y70870D01*
X120630D01*
X123900Y67600D01*
X125400D01*
X126000Y67000D01*
G01X78500Y82250D02*
X76790D01*
X74071Y79531D01*
Y74429D01*
X78000Y70500D01*
X109530D01*
X111160Y68870D01*
X119130D01*
X126000Y62000D01*
G01X75500D02*
X80500D01*
X84000Y65500D01*
X87000D01*
X88440Y64060D01*
X119939D01*
X124999Y59000D01*
X143741D01*
X146350Y61609D01*
Y63391D01*
X147609Y64650D01*
X153321D01*
X157400Y68729D01*
Y72600D01*
X156000Y74000D01*
Y82900D01*
X174600Y101500D01*
X216500D01*
X275000Y160000D01*
X307000D01*
X307500Y160500D01*
G01X76321Y78300D02*
X77917D01*
X86750Y87133D01*
Y103250D01*
X80000Y110000D01*
Y128000D01*
X75500Y132500D01*
X72000D01*
X69500Y130000D01*
G01X74000D02*
X77814Y126186D01*
Y109186D01*
X81500Y105500D01*
Y88482D01*
X81050Y88032D01*
Y84800D01*
X78500Y82250D01*
G01X87000Y125500D02*
X86500D01*
X79000Y133000D01*
Y157641D01*
X90859Y169500D01*
X203750D01*
X245000Y210750D01*
X256250D01*
X258000Y212500D01*
X300750D01*
X302500Y210750D01*
X321994D01*
X323394Y209350D01*
X358504D01*
X360854Y207000D01*
X370280D01*
X385380Y191900D01*
X392479D01*
X394131Y190248D01*
X395067D01*
G01X76100Y154400D02*
X75900D01*
X72800Y157500D01*
Y164300D01*
X75500Y167000D01*
X82000D01*
X85750Y170750D01*
Y198250D01*
X83500Y200500D01*
Y205500D01*
X88000Y210000D01*
Y222181D01*
X91450Y225631D01*
Y230829D01*
X93121Y232500D01*
X97500D01*
X116400Y251400D01*
X202729D01*
X229000Y277671D01*
Y314670D01*
X246330Y332000D01*
X270170D01*
X277085Y325085D01*
X296785D01*
X298700Y327000D01*
G01X75950Y164200D02*
X76750Y165000D01*
X82829D01*
X88000Y170171D01*
Y173500D01*
X90500Y176000D01*
Y178500D01*
X87750Y181250D01*
Y199749D01*
X90000Y201999D01*
Y221352D01*
X93450Y224802D01*
Y230000D01*
X93950Y230500D01*
X98600D01*
X117500Y249400D01*
X203558D01*
X231000Y276842D01*
Y313841D01*
X247159Y330000D01*
X269341D01*
X276920Y322421D01*
X278855D01*
X279355Y321921D01*
Y320270D01*
X279855Y319770D01*
X281355D01*
X281855Y320270D01*
Y321921D01*
X282355Y322421D01*
X283855D01*
X284355Y321921D01*
Y319710D01*
X284855Y319210D01*
X286355D01*
X286855Y319710D01*
Y321921D01*
X287355Y322421D01*
X288855D01*
X289355Y321921D01*
Y319710D01*
X289855Y319210D01*
X291355D01*
X291855Y319710D01*
Y321921D01*
X292355Y322421D01*
X297621D01*
X298700Y323500D01*
G01X63800Y274000D02*
X64248Y273552D01*
Y266452D01*
X76900Y253800D01*
Y233100D01*
X79500Y230500D01*
X82500D01*
G01X75500Y282500D02*
X73650Y280650D01*
Y273409D01*
X75200Y271859D01*
Y258329D01*
X77631Y255898D01*
X81081D01*
X82398Y254581D01*
Y252715D01*
X81750Y252067D01*
Y248009D01*
X80213Y246472D01*
Y235213D01*
X79500Y234500D01*
G01X93500Y125000D02*
X90000Y128500D01*
Y131500D01*
X81000Y140500D01*
Y152804D01*
X88596Y160400D01*
X95243D01*
X96843Y162000D01*
X102000D01*
X103600Y160400D01*
X203056D01*
X248906Y206250D01*
X259250D01*
X261000Y208000D01*
X298000D01*
X299750Y206250D01*
X319750D01*
X321150Y204850D01*
X356638D01*
X359179Y202309D01*
X368605D01*
X382954Y187960D01*
X385888D01*
G01X145900Y75200D02*
Y77900D01*
X139800Y84000D01*
X125200D01*
X107000Y102200D01*
Y134001D01*
X98501Y142500D01*
X92500D01*
X90500Y144500D01*
G01X151200Y75191D02*
Y77150D01*
X142350Y86000D01*
X129650D01*
X109500Y106150D01*
Y134999D01*
X98999Y145500D01*
X95500D01*
G01X385126Y183874D02*
X382795D01*
X367360Y199309D01*
X357935D01*
X355394Y201850D01*
X312122D01*
X310522Y200250D01*
X306500D01*
X304250Y202500D01*
X298500D01*
X296000Y205000D01*
X263500D01*
X261000Y202500D01*
X249500D01*
X246800Y199800D01*
X246700D01*
X202700Y155800D01*
X96600D01*
X93900Y158500D01*
X88818D01*
X82750Y152432D01*
Y141750D01*
X93500Y131000D01*
Y130000D01*
G01X96500Y140000D02*
Y135500D01*
X105000Y127000D01*
Y100000D01*
X108405Y96595D01*
Y95887D01*
X107103Y94585D01*
Y93877D01*
X108163Y92817D01*
X108871D01*
X110173Y94119D01*
X110881D01*
X111941Y93059D01*
Y92351D01*
X110639Y91049D01*
Y90341D01*
X111699Y89281D01*
X112407D01*
X113709Y90583D01*
X114417D01*
X115477Y89523D01*
Y88815D01*
X114175Y87513D01*
Y86805D01*
X115235Y85745D01*
X115943D01*
X117245Y87047D01*
X117953D01*
X119013Y85987D01*
Y85279D01*
X117711Y83977D01*
Y83269D01*
X118771Y82209D01*
X119479D01*
X120781Y83511D01*
X121489D01*
X123500Y81500D01*
X133099D01*
X133599Y81000D01*
Y79900D01*
X134099Y79400D01*
X135599D01*
X136099Y79900D01*
Y81000D01*
X136599Y81500D01*
X138470D01*
X142070Y77900D01*
G01X142000Y69535D02*
X138685Y72850D01*
X134651D01*
X128501Y79000D01*
X117690D01*
X102500Y94190D01*
Y126000D01*
X91500Y137000D01*
Y140000D01*
G01X387740Y182090D02*
X382457D01*
X366738Y197809D01*
X357313D01*
X354772Y200350D01*
X312744D01*
X311144Y198750D01*
X299750D01*
X295000Y203500D01*
X268500D01*
X265000Y200000D01*
Y181252D01*
X237748Y154000D01*
X95100D01*
X93900Y155200D01*
G01X386810Y179974D02*
X386444Y180340D01*
X382085D01*
X366116Y196309D01*
X356691D01*
X354150Y198850D01*
X313366D01*
X311766Y197250D01*
X298250D01*
X294000Y201500D01*
X269500D01*
X267000Y199000D01*
Y181000D01*
X237000Y151000D01*
X95200D01*
G01X389000Y191000D02*
X384158D01*
X369849Y205309D01*
X360423D01*
X357882Y207850D01*
X322772D01*
X321372Y209250D01*
X301750D01*
X300000Y211000D01*
X259000D01*
X257250Y209250D01*
X247662D01*
X201904Y163492D01*
X106008D01*
X101500Y168000D01*
X97500D01*
X94500Y165000D01*
Y163000D01*
G01X390500Y194000D02*
X386500Y198000D01*
X383524D01*
X371024Y210500D01*
X361598D01*
X359748Y212350D01*
X350650D01*
X348080Y214920D01*
Y217891D01*
X345721Y220250D01*
X334250D01*
X328750Y214750D01*
X304500D01*
X300000Y219250D01*
X138751D01*
X96750Y177249D01*
Y172750D01*
X97500Y172000D01*
G01X390814Y195685D02*
X385950Y200549D01*
Y204550D01*
X382500Y208000D01*
Y209834D01*
X379334Y213000D01*
X377378D01*
X373628Y216750D01*
X359750D01*
X358350Y215350D01*
X352150D01*
X351080Y216420D01*
Y219135D01*
X346965Y223250D01*
X332778D01*
X328028Y218500D01*
X318622D01*
X315472Y221650D01*
X310350D01*
X305450Y226550D01*
X133672D01*
X93500Y186378D01*
Y179999D01*
X92500Y178999D01*
Y174500D01*
X92000Y174000D01*
Y173000D01*
G01X95500Y192000D02*
X97000Y193500D01*
X98500D01*
X133050Y228050D01*
X306450D01*
X311350Y223150D01*
X314150D01*
X315000Y224000D01*
X331406D01*
X332156Y224750D01*
X351432D01*
X354832Y228150D01*
X364350D01*
X378086Y214414D01*
X379193D01*
X383914Y209693D01*
Y208586D01*
X387200Y205300D01*
Y201300D01*
X391000Y197500D01*
G01X402942Y205996D02*
X401392Y207546D01*
Y215608D01*
X396750Y220250D01*
Y234750D01*
X394000Y237500D01*
Y248878D01*
X389928Y252950D01*
X383050D01*
X377000Y259000D01*
X374792D01*
X373542Y257750D01*
X368750D01*
X365000Y254000D01*
X349563D01*
X346713Y251150D01*
X328744D01*
X325744Y248150D01*
X304468D01*
X294868Y238550D01*
X254150D01*
X249500Y243200D01*
X234800D01*
X230300Y238700D01*
X117900D01*
X102400Y223200D01*
X96800D01*
X93500Y219900D01*
Y200000D01*
X92000Y198500D01*
Y195499D01*
X92750Y194749D01*
Y190750D01*
X90500Y188500D01*
G01X399005Y205996D02*
X397180Y207821D01*
Y215564D01*
X391250Y221494D01*
Y224640D01*
X392500Y225890D01*
Y233500D01*
X382500Y243500D01*
X372000D01*
X370000Y245500D01*
Y247000D01*
X364500Y252500D01*
X350185D01*
X347335Y249650D01*
X339150D01*
X333950Y244450D01*
X323020D01*
X320820Y246650D01*
X305090D01*
X295490Y237050D01*
X251050D01*
X246400Y241700D01*
X238200D01*
X233700Y237200D01*
X119100D01*
X103400Y221500D01*
X97600D01*
X95000Y218900D01*
Y197500D01*
X94500Y197000D01*
G01X406879Y202059D02*
X405000Y203938D01*
Y214999D01*
X401250Y218749D01*
Y234250D01*
X395500Y240000D01*
Y249500D01*
X390550Y254450D01*
X384160D01*
X378110Y260500D01*
X374170D01*
X372920Y259250D01*
X366909D01*
X363159Y255500D01*
X348941D01*
X346091Y252650D01*
X328122D01*
X325122Y249650D01*
X303846D01*
X294246Y240050D01*
X255250D01*
X250600Y244700D01*
X232800D01*
X230000Y241900D01*
X118500D01*
X101400Y224800D01*
X96278D01*
X92000Y220522D01*
Y201000D01*
X90500Y199500D01*
Y193500D01*
G01X99000Y197500D02*
X96500Y200000D01*
Y207500D01*
X121550Y232550D01*
X297356D01*
X302956Y238150D01*
X325349D01*
X327499Y236000D01*
X334500D01*
X337750Y239250D01*
X347945D01*
X349445Y240750D01*
X352555D01*
X354805Y238500D01*
X361814D01*
X364321Y235993D01*
X376263D01*
X383000Y229256D01*
Y218000D01*
X389360Y211640D01*
Y204070D01*
X393210Y200220D01*
G01X95900Y278900D02*
X94500Y277500D01*
Y260300D01*
X87000Y252800D01*
Y246500D01*
X82600Y242100D01*
Y235200D01*
X84500Y233300D01*
Y231541D01*
X84650Y231391D01*
Y229609D01*
X84500Y229459D01*
Y218000D01*
G01X95700Y227500D02*
X99700D01*
X115600Y243400D01*
X228100D01*
X230900Y246200D01*
X251500D01*
X256150Y241550D01*
X284650D01*
X303500Y260400D01*
X313000D01*
X315750Y257650D01*
X326567D01*
X327567Y256650D01*
X344433D01*
X346000Y258217D01*
Y260683D01*
X347567Y262250D01*
X353250D01*
X356000Y265000D01*
X359501D01*
X361251Y263250D01*
X371262D01*
X372512Y264500D01*
X386329D01*
X401350Y249479D01*
Y242000D01*
X407000Y236350D01*
Y228682D01*
X413000Y222682D01*
Y204850D01*
X413850Y204000D01*
X416000D01*
X417000Y203000D01*
Y200500D01*
X417500Y200000D01*
X419500D01*
X420500Y199000D01*
Y188438D01*
X422627Y186311D01*
G01X96500Y235500D02*
X114400Y253400D01*
X199341D01*
X227000Y281059D01*
Y315499D01*
X252251Y340750D01*
X338250D01*
X343250Y345750D01*
X353750D01*
X364000Y356000D01*
X382000D01*
X393500Y344500D01*
X423817D01*
X424567Y343750D01*
X431921D01*
X435171Y347000D01*
X441500D01*
X455000Y333500D01*
X459000D01*
X465500Y327000D01*
Y318958D01*
X472900Y311558D01*
Y288100D01*
X486350Y274650D01*
Y235569D01*
X478000Y227219D01*
Y224500D01*
X471700Y218200D01*
Y211763D01*
X469870Y209933D01*
G01X112880Y73020D02*
X121480D01*
X124750Y69750D01*
X134750D01*
X137500Y67000D01*
X143500D01*
X149000Y72500D01*
X152000D01*
X154000Y74500D01*
Y83900D01*
X173721Y103621D01*
X215621D01*
X276000Y164000D01*
X303500D01*
G01X383500Y185500D02*
X383291D01*
X367982Y200809D01*
X358557D01*
X356016Y203350D01*
X311500D01*
X309900Y201750D01*
X307250D01*
X305000Y204000D01*
X299500D01*
X297000Y206500D01*
X262000D01*
X259500Y204000D01*
X248778D01*
X202878Y158100D01*
X99400D01*
X98500Y159000D01*
G01Y165500D02*
X101000D01*
X104508Y161992D01*
X202526D01*
X248284Y207750D01*
X258250D01*
X260000Y209500D01*
X299250D01*
X301000Y207750D01*
X320750D01*
X322150Y206350D01*
X357260D01*
X359801Y203809D01*
X369227D01*
X383536Y189500D01*
X386500D01*
G01X99000Y175500D02*
Y177000D01*
X139750Y217750D01*
X299378D01*
X304878Y212250D01*
X322616D01*
X324016Y210850D01*
X334850D01*
X335500Y211500D01*
Y214500D01*
X338750Y217750D01*
X341432D01*
X348332Y210850D01*
X359126D01*
X360976Y209000D01*
X370402D01*
X386402Y193000D01*
X390000D01*
G01X99000Y188500D02*
X131250Y220750D01*
X306250D01*
X306850Y220150D01*
X314850D01*
X318500Y216500D01*
X328150D01*
X333400Y221750D01*
X346343D01*
X349580Y218513D01*
Y215542D01*
X351272Y213850D01*
X358972D01*
X360372Y215250D01*
X373006D01*
X377000Y211256D01*
Y210666D01*
X384091Y203575D01*
Y200091D01*
G01X391130Y209933D02*
Y216818D01*
X386500Y221448D01*
Y232500D01*
X384500Y234500D01*
Y237500D01*
X382500Y239500D01*
X372500D01*
X370493Y237493D01*
X364944D01*
X361687Y240750D01*
X359568D01*
X357250Y243068D01*
Y243433D01*
X355933Y244750D01*
X346972D01*
X343672Y241450D01*
X317950D01*
X316150Y239650D01*
X302334D01*
X296734Y234050D01*
X120300D01*
X100250Y214000D01*
X97500D01*
G01X387193Y209933D02*
Y212307D01*
X381500Y218000D01*
Y228634D01*
X375641Y234493D01*
X359343D01*
X358086Y235750D01*
X355433D01*
X351933Y239250D01*
X350067D01*
X348750Y237933D01*
Y237000D01*
X343000Y231250D01*
X332749D01*
X329499Y234500D01*
X326459D01*
X325459Y233500D01*
X322080D01*
X318930Y236650D01*
X303578D01*
X297978Y231050D01*
X123550D01*
X99000Y206500D01*
G01Y201500D02*
Y203000D01*
X125550Y229550D01*
X308450D01*
X310350Y227650D01*
X314650D01*
X317500Y230500D01*
X324500D01*
X325500Y229500D01*
X334750D01*
X337500Y226750D01*
X351250D01*
X354150Y229650D01*
X378350D01*
X380000Y228000D01*
Y217500D01*
X384814Y212686D01*
Y208959D01*
X388300Y205473D01*
Y202427D01*
X392605Y198122D01*
X395067D01*
G01Y202059D02*
X393200Y203926D01*
Y216870D01*
X388000Y222070D01*
Y233500D01*
X386000Y235500D01*
Y237500D01*
X382500Y241000D01*
X370426D01*
X367933Y243493D01*
X364440D01*
X357433Y250500D01*
X352000D01*
X348500Y247000D01*
X346141D01*
X342091Y242950D01*
X316450D01*
X314650Y241150D01*
X301712D01*
X296112Y235550D01*
X119572D01*
X102522Y218500D01*
X98500D01*
G01X198135Y36500D02*
X193000D01*
X189000Y40500D01*
Y46500D01*
X176000Y59500D01*
Y68010D01*
X173170Y70840D01*
G01X180390Y70720D02*
X178760Y69090D01*
Y62499D01*
X180019Y61240D01*
X181361D01*
X182518Y60083D01*
X183226D01*
X185417Y62274D01*
X186125D01*
X187185Y61214D01*
Y60506D01*
X184994Y58315D01*
Y57607D01*
X186056Y56545D01*
Y53945D01*
X191535Y48466D01*
Y41200D01*
G01X188900Y54960D02*
X199360Y44500D01*
X235500D01*
X239650Y48650D01*
X243500D01*
G01X208160Y73990D02*
Y71840D01*
X216400Y63600D01*
X223500D01*
X231500Y55600D01*
X253500D01*
X259100Y50000D01*
X283000D01*
X288600Y55600D01*
X304564D01*
X306864Y57900D01*
X311764D01*
X313874Y60010D01*
X331760D01*
X338150Y66400D01*
X348600D01*
X350700Y64300D01*
X363200D01*
X366140Y61360D01*
X478160D01*
X487200Y70400D01*
X508800D01*
X513200Y66000D01*
G01X509000Y340500D02*
X506750Y342750D01*
X504579D01*
X496829Y350500D01*
X476671D01*
X475671Y349500D01*
X452000D01*
X448500Y353000D01*
X441500D01*
X436750Y357750D01*
X429750D01*
X425500Y353500D01*
Y352000D01*
X422500Y349000D01*
X395500D01*
X384500Y360000D01*
X378728D01*
X378228Y360500D01*
Y366500D01*
X377728Y367000D01*
X376228D01*
X375728Y366500D01*
Y360500D01*
X375228Y360000D01*
X373728D01*
X373228Y360500D01*
Y366500D01*
X372728Y367000D01*
X371228D01*
X370728Y366500D01*
Y360500D01*
X370228Y360000D01*
X367684D01*
X367184Y360500D01*
Y362000D01*
X366684Y362500D01*
X365184D01*
X364684Y362000D01*
Y360500D01*
X364184Y360000D01*
X362342D01*
X352463Y350121D01*
X228121D01*
X225500Y347500D01*
G01X504500Y340500D02*
X504000D01*
X496000Y348500D01*
X477500D01*
X472000Y343000D01*
X455500D01*
X447500Y351000D01*
X440000D01*
X435250Y355750D01*
X430750D01*
X429000Y354000D01*
Y350000D01*
X426000Y347000D01*
X394500D01*
X383500Y358000D01*
X363171D01*
X353171Y348000D01*
X230500D01*
X230000Y347500D01*
G01X252700Y44000D02*
Y35727D01*
X254527Y33900D01*
G01X255400Y290100D02*
X267500Y278000D01*
X306500D01*
X315000Y269500D01*
Y268000D01*
X317000Y266000D01*
X318541D01*
X326791Y274250D01*
X349750D01*
X354000Y278500D01*
X361903D01*
X364153Y276250D01*
X366847D01*
X369097Y278500D01*
X390670D01*
X396670Y272500D01*
X400750D01*
X418940Y254310D01*
Y243810D01*
X425771Y236979D01*
Y233271D01*
X423500Y231000D01*
Y222500D01*
X424250Y221750D01*
Y213750D01*
X425000Y213000D01*
X427114D01*
X429114Y211000D01*
Y195571D01*
X434437Y190248D01*
G01X438374Y217807D02*
Y219674D01*
X439000Y220300D01*
Y240400D01*
X432750Y246650D01*
Y262279D01*
X416800Y278229D01*
Y306800D01*
X409600Y314000D01*
X405400D01*
X401700Y317700D01*
X391600D01*
X388050Y321250D01*
X349250D01*
X340500Y312500D01*
X311500D01*
X308500Y309500D01*
X298000D01*
X297000Y310500D01*
G01X477500Y170500D02*
X475500Y168500D01*
X382101D01*
X380301Y170300D01*
X370300D01*
X368500Y172100D01*
X349400D01*
X349000Y171700D01*
X322200D01*
X320500Y170000D01*
G01X426564Y186311D02*
X428214Y187961D01*
Y199000D01*
X427354Y199860D01*
X426140D01*
X424690Y201310D01*
Y211310D01*
X421833Y214167D01*
Y222333D01*
X417500Y226666D01*
Y231500D01*
X419000Y233000D01*
Y237500D01*
X416900Y239600D01*
Y253100D01*
X399500Y270500D01*
X395841D01*
X394091Y272250D01*
X379933D01*
X378933Y271250D01*
X377067D01*
X376067Y272250D01*
X365324D01*
X362644Y274930D01*
X357339D01*
X354659Y272250D01*
X327620D01*
X319720Y264350D01*
X319679D01*
X318933Y263604D01*
X316567D01*
X312000Y268171D01*
Y269000D01*
G01Y256500D02*
X316800Y251700D01*
X324342D01*
X327292Y254650D01*
X345262D01*
X348112Y257500D01*
X362330D01*
X366080Y261250D01*
X372091D01*
X373341Y262500D01*
X379069D01*
X384594Y256975D01*
X391025D01*
X400000Y248000D01*
Y239500D01*
X403250Y236250D01*
Y226068D01*
X409166Y220152D01*
Y200864D01*
X409890Y200140D01*
X415360D01*
X417378Y198122D01*
X418690D01*
G01X365000Y268000D02*
X364000Y269000D01*
X355660D01*
X354410Y270250D01*
X335292D01*
X334000Y268958D01*
Y263500D01*
X332500Y262000D01*
X326390D01*
X324390Y260000D01*
X316500D01*
X312000Y264500D01*
G01X318000Y268500D02*
X326400Y276900D01*
X349400D01*
X356000Y283500D01*
X377500D01*
X377650Y283350D01*
X390333D01*
X391650Y282033D01*
Y280349D01*
X396749Y275250D01*
X401500D01*
X405500Y271250D01*
X412250D01*
X423900Y259600D01*
Y241600D01*
X428000Y237500D01*
Y222000D01*
X428750Y221250D01*
Y213250D01*
X430500Y211500D01*
Y196000D01*
X432315Y194185D01*
X434437D01*
G01X312500Y307500D02*
X315500Y310500D01*
X341499D01*
X349999Y319000D01*
X385400D01*
X388700Y315700D01*
X399117D01*
X406817Y308000D01*
X408800D01*
X410750Y306050D01*
Y299567D01*
X411700Y298617D01*
Y280500D01*
X430100Y262100D01*
Y245774D01*
X434437Y241437D01*
Y217807D01*
G01X329433Y-125500D02*
Y-133000D01*
X333167D01*
G01X340480D02*
Y-128000D01*
G01Y-128875D02*
X340107Y-128375D01*
X339547Y-128125D01*
X338893Y-128000D01*
X338240Y-128250D01*
X337680Y-128750D01*
X337307Y-129500D01*
X337120Y-130500D01*
X337307Y-131500D01*
X337680Y-132250D01*
X338240Y-132750D01*
X338893Y-133000D01*
X339547Y-132875D01*
X340107Y-132500D01*
X340480Y-132000D01*
G01X344340Y-135250D02*
X344900Y-135500D01*
X345647Y-135250D01*
X346113Y-134750D01*
X346487Y-134125D01*
X347047Y-132125D01*
X348260Y-128000D01*
G01X345273D02*
X347047Y-132125D01*
G01X352400Y-129625D02*
X355387D01*
X355107Y-128750D01*
X354640Y-128250D01*
X353987Y-128000D01*
X353333Y-128125D01*
X352773Y-128500D01*
X352400Y-129375D01*
X352213Y-130125D01*
Y-130875D01*
X352400Y-131625D01*
X352867Y-132375D01*
X353427Y-132875D01*
X354080Y-133000D01*
X354733Y-132750D01*
X355387Y-132000D01*
G01X359993Y-133000D02*
Y-128000D01*
G01Y-129000D02*
X360460Y-128500D01*
X360927Y-128125D01*
X361580Y-128000D01*
X362047Y-128125D01*
X362607Y-128500D01*
G01X368800Y-133250D02*
X368613Y-133125D01*
Y-132875D01*
X368800Y-132750D01*
X368987Y-132875D01*
Y-133125D01*
X368800Y-133250D01*
G01Y-129875D02*
X368613Y-129750D01*
Y-129500D01*
X368800Y-129375D01*
X368987Y-129500D01*
Y-129750D01*
X368800Y-129875D01*
G01X336747Y-120500D02*
Y-113000D01*
X338613D01*
X339360Y-113375D01*
X339920Y-113875D01*
X340387Y-114625D01*
X340760Y-115500D01*
X340853Y-116750D01*
X340760Y-118000D01*
X340387Y-118875D01*
X339920Y-119625D01*
X339360Y-120125D01*
X338613Y-120500D01*
X336747D01*
G01X347980D02*
Y-115500D01*
G01Y-116375D02*
X347607Y-115875D01*
X347047Y-115625D01*
X346393Y-115500D01*
X345740Y-115750D01*
X345180Y-116250D01*
X344807Y-117000D01*
X344620Y-118000D01*
X344807Y-119000D01*
X345180Y-119750D01*
X345740Y-120250D01*
X346393Y-120500D01*
X347047Y-120375D01*
X347607Y-120000D01*
X347980Y-119500D01*
G01X353800Y-113000D02*
Y-120500D01*
G01X352493Y-115500D02*
X355107D01*
G01X359900Y-117125D02*
X362887D01*
X362607Y-116250D01*
X362140Y-115750D01*
X361487Y-115500D01*
X360833Y-115625D01*
X360273Y-116000D01*
X359900Y-116875D01*
X359713Y-117625D01*
Y-118375D01*
X359900Y-119125D01*
X360367Y-119875D01*
X360927Y-120375D01*
X361580Y-120500D01*
X362233Y-120250D01*
X362887Y-119500D01*
G01X368800Y-120750D02*
X368613Y-120625D01*
Y-120375D01*
X368800Y-120250D01*
X368987Y-120375D01*
Y-120625D01*
X368800Y-120750D01*
G01Y-117375D02*
X368613Y-117250D01*
Y-117000D01*
X368800Y-116875D01*
X368987Y-117000D01*
Y-117250D01*
X368800Y-117375D01*
G01X382027Y-114250D02*
X382587Y-113500D01*
X383240Y-113125D01*
X383987Y-113000D01*
X384920Y-113250D01*
X385573Y-113875D01*
X385760Y-114625D01*
X385667Y-115375D01*
X385293Y-116000D01*
X383427Y-117250D01*
X382587Y-118125D01*
X382027Y-119375D01*
X381840Y-120500D01*
X385760D01*
G01X391300Y-113000D02*
X390553Y-113250D01*
X389993Y-113875D01*
X389620Y-114625D01*
X389340Y-115625D01*
X389247Y-116750D01*
X389340Y-117875D01*
X389620Y-118875D01*
X389993Y-119625D01*
X390553Y-120250D01*
X391300Y-120500D01*
X392047Y-120250D01*
X392607Y-119625D01*
X392980Y-118875D01*
X393260Y-117875D01*
X393353Y-116750D01*
X393260Y-115625D01*
X392980Y-114625D01*
X392607Y-113875D01*
X392047Y-113250D01*
X391300Y-113000D01*
G01X397027Y-114250D02*
X397587Y-113500D01*
X398240Y-113125D01*
X398987Y-113000D01*
X399920Y-113250D01*
X400573Y-113875D01*
X400760Y-114625D01*
X400667Y-115375D01*
X400293Y-116000D01*
X398427Y-117250D01*
X397587Y-118125D01*
X397027Y-119375D01*
X396840Y-120500D01*
X400760D01*
G01X404527Y-114250D02*
X405087Y-113500D01*
X405740Y-113125D01*
X406487Y-113000D01*
X407420Y-113250D01*
X408073Y-113875D01*
X408260Y-114625D01*
X408167Y-115375D01*
X407793Y-116000D01*
X405927Y-117250D01*
X405087Y-118125D01*
X404527Y-119375D01*
X404340Y-120500D01*
X408260D01*
G01X412587Y-118000D02*
X415013D01*
G01X421300Y-113000D02*
X420553Y-113250D01*
X419993Y-113875D01*
X419620Y-114625D01*
X419340Y-115625D01*
X419247Y-116750D01*
X419340Y-117875D01*
X419620Y-118875D01*
X419993Y-119625D01*
X420553Y-120250D01*
X421300Y-120500D01*
X422047Y-120250D01*
X422607Y-119625D01*
X422980Y-118875D01*
X423260Y-117875D01*
X423353Y-116750D01*
X423260Y-115625D01*
X422980Y-114625D01*
X422607Y-113875D01*
X422047Y-113250D01*
X421300Y-113000D01*
G01X427027Y-114250D02*
X427587Y-113500D01*
X428240Y-113125D01*
X428987Y-113000D01*
X429920Y-113250D01*
X430573Y-113875D01*
X430760Y-114625D01*
X430667Y-115375D01*
X430293Y-116000D01*
X428427Y-117250D01*
X427587Y-118125D01*
X427027Y-119375D01*
X426840Y-120500D01*
X430760D01*
G01X435087Y-118000D02*
X437513D01*
G01X442027Y-114250D02*
X442587Y-113500D01*
X443240Y-113125D01*
X443987Y-113000D01*
X444920Y-113250D01*
X445573Y-113875D01*
X445760Y-114625D01*
X445667Y-115375D01*
X445293Y-116000D01*
X443427Y-117250D01*
X442587Y-118125D01*
X442027Y-119375D01*
X441840Y-120500D01*
X445760D01*
G01X449247Y-119375D02*
X449807Y-120000D01*
X450460Y-120375D01*
X451300Y-120500D01*
X452140Y-120250D01*
X452793Y-119750D01*
X453260Y-118875D01*
X453353Y-117875D01*
X453167Y-116875D01*
X452700Y-116250D01*
X452047Y-115750D01*
X451393Y-115625D01*
X450740Y-115750D01*
X449900Y-116250D01*
X450180Y-113000D01*
X452700D01*
G01X336933Y-108000D02*
Y-100500D01*
X339267D01*
X340013Y-100875D01*
X340480Y-101375D01*
X340667Y-102375D01*
X340480Y-103375D01*
X339920Y-104000D01*
X339267Y-104375D01*
X336933D01*
G01X339267D02*
X340667Y-108000D01*
G01X344900Y-104625D02*
X347887D01*
X347607Y-103750D01*
X347140Y-103250D01*
X346487Y-103000D01*
X345833Y-103125D01*
X345273Y-103500D01*
X344900Y-104375D01*
X344713Y-105125D01*
Y-105875D01*
X344900Y-106625D01*
X345367Y-107375D01*
X345927Y-107875D01*
X346580Y-108000D01*
X347233Y-107750D01*
X347887Y-107000D01*
G01X352120Y-103000D02*
X353800Y-108000D01*
X355480Y-103000D01*
G01X368800Y-108250D02*
X368613Y-108125D01*
Y-107875D01*
X368800Y-107750D01*
X368987Y-107875D01*
Y-108125D01*
X368800Y-108250D01*
G01Y-104875D02*
X368613Y-104750D01*
Y-104500D01*
X368800Y-104375D01*
X368987Y-104500D01*
Y-104750D01*
X368800Y-104875D01*
G01X383800Y-100500D02*
X383053Y-100750D01*
X382493Y-101375D01*
X382120Y-102125D01*
X381840Y-103125D01*
X381747Y-104250D01*
X381840Y-105375D01*
X382120Y-106375D01*
X382493Y-107125D01*
X383053Y-107750D01*
X383800Y-108000D01*
X384547Y-107750D01*
X385107Y-107125D01*
X385480Y-106375D01*
X385760Y-105375D01*
X385853Y-104250D01*
X385760Y-103125D01*
X385480Y-102125D01*
X385107Y-101375D01*
X384547Y-100750D01*
X383800Y-100500D01*
G01X391300Y-108000D02*
Y-100500D01*
X390180Y-102000D01*
G01Y-108000D02*
X392420D01*
G01X336933Y-95500D02*
Y-88000D01*
X339173D01*
X339920Y-88375D01*
X340480Y-89250D01*
X340667Y-90250D01*
X340480Y-91250D01*
X340013Y-92000D01*
X339173Y-92375D01*
X336933D01*
G01X344620Y-95750D02*
X347980Y-88000D01*
G01X351653Y-95500D02*
Y-88000D01*
X355947Y-95500D01*
Y-88000D01*
G01X368800Y-95750D02*
X368613Y-95625D01*
Y-95375D01*
X368800Y-95250D01*
X368987Y-95375D01*
Y-95625D01*
X368800Y-95750D01*
G01Y-92375D02*
X368613Y-92250D01*
Y-92000D01*
X368800Y-91875D01*
X368987Y-92000D01*
Y-92250D01*
X368800Y-92375D01*
G01X381933Y-95500D02*
Y-88000D01*
X384267D01*
X385013Y-88375D01*
X385480Y-88875D01*
X385667Y-89875D01*
X385480Y-90875D01*
X384920Y-91500D01*
X384267Y-91875D01*
X381933D01*
G01X384267D02*
X385667Y-95500D01*
G01X392420D02*
Y-88000D01*
X388967Y-93375D01*
X393633D01*
G01X398800Y-88000D02*
X398053Y-88250D01*
X397493Y-88875D01*
X397120Y-89625D01*
X396840Y-90625D01*
X396747Y-91750D01*
X396840Y-92875D01*
X397120Y-93875D01*
X397493Y-94625D01*
X398053Y-95250D01*
X398800Y-95500D01*
X399547Y-95250D01*
X400107Y-94625D01*
X400480Y-93875D01*
X400760Y-92875D01*
X400853Y-91750D01*
X400760Y-90625D01*
X400480Y-89625D01*
X400107Y-88875D01*
X399547Y-88250D01*
X398800Y-88000D01*
G01X406300D02*
X405553Y-88250D01*
X404993Y-88875D01*
X404620Y-89625D01*
X404340Y-90625D01*
X404247Y-91750D01*
X404340Y-92875D01*
X404620Y-93875D01*
X404993Y-94625D01*
X405553Y-95250D01*
X406300Y-95500D01*
X407047Y-95250D01*
X407607Y-94625D01*
X407980Y-93875D01*
X408260Y-92875D01*
X408353Y-91750D01*
X408260Y-90625D01*
X407980Y-89625D01*
X407607Y-88875D01*
X407047Y-88250D01*
X406300Y-88000D01*
G01X412027Y-92375D02*
X412680Y-91500D01*
X413240Y-91000D01*
X413987Y-90750D01*
X414640Y-91000D01*
X415107Y-91500D01*
X415480Y-92250D01*
X415573Y-93125D01*
X415480Y-93875D01*
X415107Y-94625D01*
X414547Y-95250D01*
X413893Y-95500D01*
X413147Y-95250D01*
X412493Y-94500D01*
X412120Y-93375D01*
X412027Y-92125D01*
X412213Y-90500D01*
X412493Y-89625D01*
X412960Y-88750D01*
X413613Y-88125D01*
X414267Y-88000D01*
X414920Y-88250D01*
X415387Y-88875D01*
G01X420087Y-93000D02*
X422513D01*
G01X429547Y-91500D02*
X429920Y-91125D01*
X430200Y-90500D01*
X430387Y-89625D01*
X430200Y-88875D01*
X429827Y-88375D01*
X429173Y-88000D01*
X426653D01*
Y-95500D01*
X429733D01*
X430387Y-95000D01*
X430760Y-94250D01*
X430947Y-93375D01*
X430760Y-92500D01*
X430200Y-91750D01*
X429547Y-91500D01*
X426653D01*
G01X436300Y-88000D02*
X435553Y-88250D01*
X434993Y-88875D01*
X434620Y-89625D01*
X434340Y-90625D01*
X434247Y-91750D01*
X434340Y-92875D01*
X434620Y-93875D01*
X434993Y-94625D01*
X435553Y-95250D01*
X436300Y-95500D01*
X437047Y-95250D01*
X437607Y-94625D01*
X437980Y-93875D01*
X438260Y-92875D01*
X438353Y-91750D01*
X438260Y-90625D01*
X437980Y-89625D01*
X437607Y-88875D01*
X437047Y-88250D01*
X436300Y-88000D01*
G01X443800D02*
X443053Y-88250D01*
X442493Y-88875D01*
X442120Y-89625D01*
X441840Y-90625D01*
X441747Y-91750D01*
X441840Y-92875D01*
X442120Y-93875D01*
X442493Y-94625D01*
X443053Y-95250D01*
X443800Y-95500D01*
X444547Y-95250D01*
X445107Y-94625D01*
X445480Y-93875D01*
X445760Y-92875D01*
X445853Y-91750D01*
X445760Y-90625D01*
X445480Y-89625D01*
X445107Y-88875D01*
X444547Y-88250D01*
X443800Y-88000D01*
G01X451300D02*
X450553Y-88250D01*
X449993Y-88875D01*
X449620Y-89625D01*
X449340Y-90625D01*
X449247Y-91750D01*
X449340Y-92875D01*
X449620Y-93875D01*
X449993Y-94625D01*
X450553Y-95250D01*
X451300Y-95500D01*
X452047Y-95250D01*
X452607Y-94625D01*
X452980Y-93875D01*
X453260Y-92875D01*
X453353Y-91750D01*
X453260Y-90625D01*
X452980Y-89625D01*
X452607Y-88875D01*
X452047Y-88250D01*
X451300Y-88000D01*
G01X458800Y-95500D02*
Y-88000D01*
X457680Y-89500D01*
G01Y-95500D02*
X459920D01*
G01X465087Y-93000D02*
X467513D01*
G01X473800Y-88000D02*
X473053Y-88250D01*
X472493Y-88875D01*
X472120Y-89625D01*
X471840Y-90625D01*
X471747Y-91750D01*
X471840Y-92875D01*
X472120Y-93875D01*
X472493Y-94625D01*
X473053Y-95250D01*
X473800Y-95500D01*
X474547Y-95250D01*
X475107Y-94625D01*
X475480Y-93875D01*
X475760Y-92875D01*
X475853Y-91750D01*
X475760Y-90625D01*
X475480Y-89625D01*
X475107Y-88875D01*
X474547Y-88250D01*
X473800Y-88000D01*
G01X479527Y-89250D02*
X480087Y-88500D01*
X480740Y-88125D01*
X481487Y-88000D01*
X482420Y-88250D01*
X483073Y-88875D01*
X483260Y-89625D01*
X483167Y-90375D01*
X482793Y-91000D01*
X480927Y-92250D01*
X480087Y-93125D01*
X479527Y-94375D01*
X479340Y-95500D01*
X483260D01*
G01X338500Y259000D02*
X340500Y261000D01*
Y266000D01*
X342750Y268250D01*
X353270D01*
X354520Y267000D01*
X360330D01*
X362080Y265250D01*
X370433D01*
X371683Y266500D01*
X387250D01*
X399750Y254000D01*
X402390D01*
X405750Y250640D01*
Y241500D01*
X409000Y238250D01*
Y229511D01*
X417000Y221511D01*
Y208500D01*
X417500Y208000D01*
X420250D01*
X420750Y207500D01*
Y201250D01*
X422000Y200000D01*
X423312D01*
X424812Y198500D01*
Y192000D01*
X426564Y190248D01*
G01X504000Y64500D02*
X498880Y59380D01*
X482280D01*
X479300Y56400D01*
X354100D01*
X349500Y61000D01*
G01X508500Y64500D02*
X505500Y67500D01*
X487500D01*
X478700Y58700D01*
X356300D01*
X354500Y60500D01*
Y60920D01*
G01X344000Y103000D02*
Y100500D01*
X358500Y86000D01*
Y77300D01*
X372390Y63410D01*
X477010D01*
X486590Y72990D01*
X549700D01*
X554550Y68140D01*
X565140D01*
X578850Y81850D01*
X626850D01*
X640500Y95500D01*
Y164000D01*
X628500Y176000D01*
Y189500D01*
G01X346000Y306500D02*
Y306250D01*
X346500Y305750D01*
X351933D01*
X353250Y307067D01*
Y307433D01*
X357967Y312150D01*
X382850D01*
X389450Y305550D01*
Y303909D01*
X390709Y302650D01*
X392350D01*
X402500Y292500D01*
Y290927D01*
X402000Y290427D01*
X398920D01*
X398420Y289927D01*
Y288427D01*
X398920Y287927D01*
X402000D01*
X402500Y287427D01*
Y285927D01*
X402000Y285427D01*
X398920D01*
X398420Y284927D01*
Y283427D01*
X398920Y282927D01*
X402000D01*
X402500Y282427D01*
Y277464D01*
X404964Y275000D01*
X411329D01*
X425900Y260429D01*
Y242064D01*
X431000Y236964D01*
Y224500D01*
X430500Y224000D01*
Y215000D01*
X432000Y213500D01*
Y197000D01*
X432750Y196250D01*
X435250D01*
X436560Y194940D01*
Y192500D01*
X437060Y192000D01*
X439500D01*
X441252Y190248D01*
X442311D01*
G01X351000Y308000D02*
Y309500D01*
X355650Y314150D01*
X383850D01*
X391050Y306950D01*
X392491D01*
X393750Y305691D01*
Y304250D01*
X405000Y293000D01*
Y278500D01*
X406000Y277500D01*
X411658D01*
X427900Y261258D01*
Y245145D01*
X432500Y240545D01*
Y216140D01*
X433000Y215640D01*
X435360D01*
X436500Y214500D01*
Y197000D01*
X437500Y196000D01*
X440496D01*
X442311Y194185D01*
G01X369000Y413500D02*
X366500Y416000D01*
X363000D01*
X360000Y413000D01*
X355601D01*
X348279Y405678D01*
G01X361124Y349876D02*
X365248Y354000D01*
X367500D01*
X377500Y344000D01*
X387683D01*
X391433Y340250D01*
X410933D01*
X411683Y339500D01*
X425683D01*
X446683Y318500D01*
X453842D01*
X459250Y313092D01*
Y310067D01*
X460158Y309159D01*
Y305158D01*
X457500Y302500D01*
Y283000D01*
X466300Y274200D01*
X468300D01*
X471500Y271000D01*
Y263500D01*
X467850Y259850D01*
Y248351D01*
X463500Y244001D01*
Y229001D01*
X460100Y225601D01*
Y197100D01*
X459000Y196000D01*
X457001D01*
X455186Y194185D01*
X454122D01*
G01X375500Y350500D02*
X377200Y348800D01*
X386200D01*
X392750Y342250D01*
X411762D01*
X412512Y341500D01*
X432500D01*
X436000Y345000D01*
X440000D01*
X454000Y331000D01*
X458500D01*
X463000Y326500D01*
Y318629D01*
X470900Y310729D01*
Y286600D01*
X478500Y279000D01*
Y270800D01*
X483750Y265550D01*
Y240250D01*
X473000Y229500D01*
Y224000D01*
X468320Y219320D01*
Y215420D01*
X469870Y213870D01*
G01X374500Y418500D02*
X383500Y427500D01*
X447500D01*
X493250Y381750D01*
X506750D01*
X511000Y377500D01*
Y365460D01*
X523190Y353270D01*
X558710D01*
X562080Y349900D01*
X567280D01*
X569400Y347780D01*
Y315600D01*
X576370Y308630D01*
X578870D01*
X584470Y303030D01*
Y299500D01*
X588000Y295970D01*
Y248330D01*
X590650Y245680D01*
G01X418690Y209933D02*
X420500Y211743D01*
Y220840D01*
X411250Y230090D01*
Y255421D01*
X405121Y261550D01*
X400451D01*
X393001Y269000D01*
X376500D01*
G01X453000Y250000D02*
X447200Y255800D01*
Y268900D01*
X442800Y273300D01*
Y294700D01*
X444700Y296600D01*
Y299800D01*
X441500Y303000D01*
Y309501D01*
X429000Y322001D01*
Y329500D01*
X426500Y332000D01*
X420500D01*
X419000Y330500D01*
X398283D01*
X398233Y330450D01*
X396367D01*
X395050Y331767D01*
Y333450D01*
X390000Y338500D01*
G01X606902Y186000D02*
X601501D01*
X600001Y184500D01*
X593320D01*
X590820Y187000D01*
X580172D01*
X575986Y191186D01*
Y214486D01*
X574000Y216472D01*
Y221500D01*
X581150Y228650D01*
Y252350D01*
X574500Y259000D01*
Y265500D01*
X555500Y284500D01*
Y294500D01*
X543500Y306500D01*
X523501D01*
X515800Y314201D01*
Y340869D01*
X509919Y346750D01*
X506237D01*
X498487Y354500D01*
X473142D01*
X469321Y358321D01*
X448179D01*
X435500Y371000D01*
X429500D01*
X422000Y363500D01*
X414000D01*
X412000Y365500D01*
X394500D01*
X391000Y362000D01*
X384000D01*
X381000Y365000D01*
G01X587500Y190000D02*
X586500Y189000D01*
X581001D01*
X578250Y191751D01*
Y213920D01*
X579000Y214670D01*
Y223671D01*
X582750Y227421D01*
Y227433D01*
X583764Y228447D01*
Y252938D01*
X576750Y259952D01*
Y266500D01*
X559000Y284250D01*
Y294001D01*
X544501Y308500D01*
X524330D01*
X517800Y315030D01*
Y341698D01*
X510748Y348750D01*
Y351252D01*
X505500Y356500D01*
X505499D01*
X505249Y356750D01*
X498749D01*
X498499Y356500D01*
X474500D01*
X470000Y361000D01*
X468616D01*
X468116Y361500D01*
Y363620D01*
X467616Y364120D01*
X466116D01*
X465616Y363620D01*
Y361500D01*
X465116Y361000D01*
X463616D01*
X463116Y361500D01*
Y363620D01*
X462616Y364120D01*
X461116D01*
X460616Y363620D01*
Y361500D01*
X460116Y361000D01*
X458616D01*
X458116Y361500D01*
Y363620D01*
X457616Y364120D01*
X456116D01*
X455616Y363620D01*
Y361500D01*
X455116Y361000D01*
X453616D01*
X453116Y361500D01*
Y363620D01*
X452616Y364120D01*
X451116D01*
X450616Y363620D01*
Y361500D01*
X450116Y361000D01*
X448500D01*
X434750Y374750D01*
X427250D01*
X421500Y369000D01*
X415000D01*
X413500Y367500D01*
X393500D01*
X391000Y365000D01*
X386500D01*
G01X389500Y370000D02*
Y370500D01*
X395500Y376500D01*
X412500D01*
X425500Y389500D01*
X453000D01*
X466000Y376500D01*
X496990D01*
X523490Y350000D01*
X559110D01*
X567000Y342110D01*
Y313000D01*
X577900Y302100D01*
X581500D01*
G01X408500Y321998D02*
X420500Y309998D01*
Y277500D01*
X435000Y263000D01*
Y250500D01*
G01X410000Y338000D02*
X413500Y334500D01*
X427999D01*
X431500Y330999D01*
Y327000D01*
X442500Y316000D01*
X454220D01*
X456500Y313720D01*
Y310500D01*
X454000Y308000D01*
Y301500D01*
X456000Y299500D01*
Y282378D01*
X466250Y272128D01*
Y269067D01*
X468500Y266817D01*
Y264500D01*
G01X448500Y250000D02*
X446000Y252500D01*
X442250D01*
X441750Y253000D01*
Y253948D01*
X441250Y254448D01*
X437600D01*
X437100Y254948D01*
Y256448D01*
X437600Y256948D01*
X441250D01*
X441750Y257448D01*
Y258948D01*
X441250Y259448D01*
X437600D01*
X437100Y259948D01*
Y261448D01*
X437600Y261948D01*
X441250D01*
X441750Y262448D01*
Y268350D01*
X439800Y270300D01*
X436100D01*
X432300Y274100D01*
Y281001D01*
X429442Y283859D01*
Y295002D01*
X428942Y295502D01*
X424700D01*
X424200Y296002D01*
Y297502D01*
X424700Y298002D01*
X428942D01*
X429442Y298502D01*
Y300002D01*
X428942Y300502D01*
X424700D01*
X424200Y301002D01*
Y302502D01*
X424700Y303002D01*
X428942D01*
X429442Y303502D01*
Y305002D01*
X428942Y305502D01*
X424700D01*
X424200Y306002D01*
Y307502D01*
X424700Y308002D01*
X428942D01*
X429442Y308502D01*
Y310075D01*
G01X421360Y359970D02*
X422970D01*
X426500Y363500D01*
X435000D01*
X443000Y355500D01*
X449500D01*
X453000Y352000D01*
X475342D01*
X475842Y352500D01*
X497658D01*
X505408Y344750D01*
X509090D01*
X513800Y340040D01*
Y307200D01*
X519850Y301150D01*
X545350D01*
X553000Y293500D01*
Y283501D01*
X572150Y264351D01*
Y250350D01*
X576000Y246500D01*
G01X413500Y373500D02*
X416000Y371000D01*
X420000D01*
X425750Y376750D01*
X456591D01*
X458332Y375009D01*
Y374303D01*
X455968Y371940D01*
Y371234D01*
X457030Y370172D01*
X457736D01*
X460100Y372535D01*
X460806D01*
X461868Y371473D01*
Y370767D01*
X459504Y368404D01*
Y367698D01*
X460566Y366636D01*
X461272D01*
X463636Y368999D01*
X464342D01*
X466029Y367312D01*
X471353D01*
X473472Y369431D01*
X495572D01*
X519800Y345203D01*
Y315859D01*
X524659Y311000D01*
X545500D01*
X566500Y290000D01*
Y281500D01*
X579000Y269000D01*
Y264500D01*
X581400Y262100D01*
G01X419000Y373500D02*
X424250Y378750D01*
X437933D01*
X440683Y381500D01*
X450317D01*
X452567Y379250D01*
X456921D01*
X464558Y371613D01*
X464561Y371612D01*
X496220D01*
X521800Y346032D01*
Y317200D01*
X526000Y313000D01*
X547000D01*
X553324Y306676D01*
X554032D01*
X555174Y307818D01*
X555882D01*
X556942Y306758D01*
Y306050D01*
X555800Y304908D01*
Y304200D01*
X556860Y303140D01*
X557568D01*
X558710Y304282D01*
X559418D01*
X560478Y303222D01*
Y302514D01*
X559336Y301372D01*
Y300664D01*
X560396Y299604D01*
X561104D01*
X562246Y300746D01*
X562954D01*
X564014Y299686D01*
Y298978D01*
X562872Y297836D01*
Y297128D01*
X563932Y296068D01*
X564640D01*
X565782Y297210D01*
X566490D01*
X567550Y296150D01*
Y295442D01*
X566408Y294300D01*
Y293592D01*
X568500Y291500D01*
Y283500D01*
X579900Y272100D01*
X581400D01*
G01Y282100D02*
X575400D01*
X571500Y286000D01*
Y288223D01*
X572000Y288723D01*
X575000D01*
X575500Y289223D01*
Y290723D01*
X575000Y291223D01*
X572000D01*
X571500Y291723D01*
Y293223D01*
X572000Y293723D01*
X575000D01*
X575500Y294223D01*
Y295723D01*
X575000Y296223D01*
X572000D01*
X571500Y296723D01*
Y298223D01*
X572000Y298723D01*
X575000D01*
X575500Y299223D01*
Y300723D01*
X575000Y301223D01*
X572000D01*
X571500Y301723D01*
Y305001D01*
X565000Y311501D01*
Y341281D01*
X558431Y347850D01*
X522811D01*
X496635Y374026D01*
X464974D01*
X453000Y386000D01*
X445541D01*
X443891Y384350D01*
X441149D01*
X440499Y385000D01*
X434501D01*
X433501Y384000D01*
X431390D01*
X431140Y383750D01*
X428860D01*
X428610Y384000D01*
X423500D01*
X420500Y381000D01*
G01X482000Y212500D02*
X477750Y208250D01*
Y206750D01*
X473000Y202000D01*
X468999D01*
X466999Y200000D01*
X465170D01*
X464000Y198830D01*
Y196500D01*
X463500Y196000D01*
X461000D01*
X460000Y195000D01*
Y193391D01*
X459109Y192500D01*
X457000D01*
X456000Y191500D01*
Y189217D01*
X455283Y188500D01*
X437224D01*
X436724Y188000D01*
Y180776D01*
X438374Y179126D01*
Y178437D01*
G01X457500Y227500D02*
X457000D01*
X454500Y225000D01*
Y223000D01*
X452000Y220500D01*
Y200500D01*
X451500Y200000D01*
X440252D01*
X438374Y198122D01*
G01Y202059D02*
X440290Y203975D01*
Y214520D01*
X439040Y215770D01*
X437230D01*
X436500Y216500D01*
Y233000D01*
G01X457500Y237400D02*
X455250Y239650D01*
Y239680D01*
X454750Y240180D01*
X451100D01*
X450600Y240680D01*
Y242180D01*
X451100Y242680D01*
X454750D01*
X455250Y243180D01*
Y244680D01*
X454750Y245180D01*
X451100D01*
X450600Y245680D01*
Y247180D01*
X451100Y247680D01*
X454750D01*
X455250Y248180D01*
Y252500D01*
X452000Y255750D01*
Y257799D01*
X452500Y258299D01*
X454000D01*
X454500Y258799D01*
Y260299D01*
X454000Y260799D01*
X452500D01*
X452000Y261299D01*
Y262799D01*
X452500Y263299D01*
X457500D01*
X458000Y263799D01*
Y265299D01*
X457500Y265799D01*
X452500D01*
X452000Y266299D01*
Y267799D01*
X452500Y268299D01*
X457500D01*
X458000Y268799D01*
Y270299D01*
X457500Y270799D01*
X452500D01*
X452000Y271299D01*
Y272799D01*
X452500Y273299D01*
X455700D01*
X456200Y273799D01*
Y275299D01*
X455700Y275799D01*
X452500D01*
X449550Y278749D01*
Y298451D01*
X446000Y302001D01*
Y309000D01*
X448500Y311500D01*
G01X461996Y209933D02*
Y211196D01*
X463900Y213100D01*
Y222900D01*
X465500Y224500D01*
Y243001D01*
X473250Y250751D01*
Y262249D01*
X474500Y263499D01*
Y276501D01*
X466900Y284101D01*
Y309071D01*
X461471Y314500D01*
X460671D01*
X447978Y327193D01*
X447270D01*
X446792Y326715D01*
X446084D01*
X445024Y327775D01*
Y328483D01*
X445502Y328961D01*
Y329669D01*
X444750Y330421D01*
Y333839D01*
X442500Y336089D01*
G01X461996Y205996D02*
X464100Y208100D01*
Y210600D01*
X466000Y212500D01*
Y221877D01*
X471000Y226877D01*
Y230329D01*
X473500Y232829D01*
Y248000D01*
X475250Y249750D01*
Y260962D01*
X476500Y262212D01*
Y278000D01*
X468900Y285600D01*
Y309900D01*
X462300Y316500D01*
X461500D01*
X447500Y330500D01*
Y334671D01*
X440671Y341500D01*
X439500D01*
G01X433000Y353500D02*
X437500Y349000D01*
X442329D01*
X455329Y336000D01*
X460000D01*
X468000Y328000D01*
Y319287D01*
X474900Y312387D01*
Y289600D01*
X488850Y275650D01*
Y235240D01*
X481000Y227390D01*
Y223999D01*
X475457Y218456D01*
Y209249D01*
X474208Y208000D01*
X473618D01*
X471520Y205902D01*
Y205312D01*
X470208Y204000D01*
X467874D01*
X465933Y202059D01*
G01X477400Y158200D02*
X477700Y158500D01*
X492001D01*
X494000Y156501D01*
Y152000D01*
X497500Y148500D01*
G01X458059Y162690D02*
X459749Y161000D01*
X475800D01*
X476800Y162000D01*
X493817D01*
X495067Y160750D01*
X497250D01*
X503000Y155000D01*
G01X458059Y178437D02*
Y177351D01*
X461196Y174214D01*
X473192D01*
X475478Y176500D01*
X480500D01*
X484134Y180134D01*
X484842D01*
X491084Y173892D01*
X491792D01*
X492852Y174952D01*
Y175660D01*
X486610Y181902D01*
Y182610D01*
X487670Y183670D01*
X488378D01*
X492320Y179728D01*
X493028D01*
X494088Y180788D01*
Y181496D01*
X490146Y185438D01*
Y186146D01*
X493500Y189500D01*
Y199817D01*
X498250Y204567D01*
Y210238D01*
X500000Y211988D01*
Y221671D01*
X518500Y240171D01*
Y248000D01*
X520500Y250000D01*
X536000D01*
X542300Y256300D01*
X545250D01*
G01X484000Y166000D02*
X481500Y168500D01*
X477873D01*
X474350Y164977D01*
X455772D01*
X454122Y166627D01*
G01X479246Y178464D02*
X476168D01*
X473704Y176000D01*
X461870D01*
X460130Y177740D01*
Y179100D01*
X458840Y180390D01*
X456106D01*
X454122Y182374D01*
G01Y178437D02*
X460345Y172214D01*
X474214D01*
X476934Y174934D01*
X485033D01*
G01X458059Y182374D02*
X459186D01*
X461060Y180500D01*
X474500D01*
X478266Y184266D01*
X482266D01*
X483500Y185500D01*
X484000D01*
G01X464000Y186871D02*
X465129Y188000D01*
X474012D01*
X476512Y190500D01*
X482599D01*
X489500Y197401D01*
Y207623D01*
X490305Y208428D01*
X490750Y208875D01*
Y213817D01*
X492750Y215817D01*
Y221751D01*
X495000Y224001D01*
Y227200D01*
X499200Y231400D01*
X500983D01*
X509350Y239767D01*
Y241633D01*
X509000Y241983D01*
Y268601D01*
X514150Y273751D01*
Y278151D01*
X532606Y296607D01*
X537500D01*
G01X539500Y292000D02*
X539400Y292100D01*
X537836D01*
X537336Y291600D01*
Y288000D01*
X536536Y287200D01*
X535636D01*
X534836Y288000D01*
Y292000D01*
X534336Y292500D01*
X531600D01*
X516500Y277400D01*
Y241000D01*
X494750Y219250D01*
Y214988D01*
X492750Y212988D01*
Y207753D01*
X491500Y206499D01*
Y194000D01*
X485664Y188164D01*
X479335D01*
X475825Y184654D01*
X465154D01*
G01X461996Y186311D02*
Y187295D01*
X464000Y189299D01*
Y191500D01*
X465000Y192500D01*
X475682D01*
X480500Y197318D01*
Y200000D01*
X482750Y202250D01*
Y206531D01*
X486750Y210531D01*
Y214469D01*
X485000Y216219D01*
Y225218D01*
X499450Y239668D01*
Y253050D01*
X497850Y254650D01*
Y279690D01*
X509800Y291640D01*
Y329188D01*
X503488Y335500D01*
X494001D01*
X483501Y346000D01*
G01X457500Y223500D02*
X456260Y222260D01*
Y197260D01*
X455230Y196230D01*
X452230D01*
X450185Y194185D01*
G01X461000Y230000D02*
X460500Y230500D01*
X457500D01*
X448500Y221500D01*
Y207681D01*
X450185Y205996D01*
G01X461000Y234500D02*
Y240000D01*
X459750Y241250D01*
Y251287D01*
X462700Y254237D01*
X465200D01*
X465700Y254737D01*
Y256237D01*
X465200Y256737D01*
X462700D01*
X462200Y257237D01*
Y258737D01*
X462700Y259237D01*
X465200D01*
X465700Y259737D01*
Y261237D01*
X465200Y261737D01*
X462700D01*
X462200Y262237D01*
Y263901D01*
X464000Y265701D01*
Y271000D01*
X454000Y281000D01*
Y286960D01*
X453500Y287460D01*
X452800D01*
X452300Y287960D01*
Y289460D01*
X452800Y289960D01*
X453500D01*
X454000Y290460D01*
Y291960D01*
X453500Y292460D01*
X452800D01*
X452300Y292960D01*
Y294460D01*
X452800Y294960D01*
X453500D01*
X454000Y295460D01*
Y297000D01*
X448000Y303000D01*
Y307000D01*
X453500Y312500D01*
X454000D01*
G01X465933Y154816D02*
X467266D01*
X469250Y156800D01*
X486090D01*
X488250Y154640D01*
Y151750D01*
X491500Y148500D01*
G01X465933Y158753D02*
X466780Y159600D01*
X477000D01*
X477700Y160300D01*
X493395D01*
X496445Y157250D01*
X498140D01*
X500250Y155140D01*
Y152250D01*
X503500Y149000D01*
G01X478500Y346000D02*
X477200Y344700D01*
Y295701D01*
X495500Y277401D01*
Y259500D01*
X494550Y258550D01*
Y238000D01*
X483000Y226450D01*
Y215390D01*
X484750Y213640D01*
Y211360D01*
X473640Y200250D01*
X469361D01*
X468000Y198889D01*
Y196252D01*
X465933Y194185D01*
G01X493700Y79161D02*
X493941D01*
X496280Y81500D01*
X500612D01*
X501112Y81000D01*
Y79270D01*
X501612Y78770D01*
X503112D01*
X503612Y79270D01*
Y81000D01*
X504112Y81500D01*
X505612D01*
X506112Y81000D01*
Y79460D01*
X506612Y78960D01*
X508112D01*
X508612Y79460D01*
Y81000D01*
X509112Y81500D01*
X510612D01*
X511112Y81000D01*
Y79460D01*
X511612Y78960D01*
X513112D01*
X513612Y79460D01*
Y81000D01*
X514112Y81500D01*
X519500D01*
G01Y75500D02*
X523000Y79000D01*
Y82000D01*
X521000Y84000D01*
X517000D01*
X516000Y85000D01*
X496000D01*
G01X485033Y174934D02*
X489467Y170500D01*
X499829D01*
X512250Y158079D01*
Y128750D01*
X536500Y104500D01*
Y100500D01*
X541000Y96000D01*
G01X481500Y193000D02*
X482000D01*
X487500Y198500D01*
Y208452D01*
X488750Y209702D01*
Y215298D01*
X487000Y217048D01*
Y224389D01*
X501061Y238450D01*
X503133D01*
X504450Y239767D01*
Y241633D01*
X503500Y242583D01*
Y282500D01*
X511200Y290200D01*
Y290211D01*
X511800Y290811D01*
Y330017D01*
X503817Y338000D01*
X496500D01*
X488500Y346000D01*
G01X531000Y285500D02*
Y277600D01*
X536000Y272600D01*
Y271500D01*
X547400Y260100D01*
Y255408D01*
X545496Y253504D01*
X542504D01*
X537000Y248000D01*
X529583D01*
X502000Y220417D01*
Y211159D01*
X500250Y209409D01*
Y203738D01*
X499000Y202488D01*
Y190750D01*
X500500Y189250D01*
Y175000D01*
X519000Y156500D01*
Y126818D01*
X547818Y98000D01*
X576500D01*
G01X580000Y104800D02*
X579500Y104300D01*
X547200D01*
X521000Y130500D01*
Y157500D01*
X504250Y174250D01*
Y193651D01*
X505500Y194901D01*
Y208829D01*
X506000Y209329D01*
Y218759D01*
X507541Y220300D01*
X512000D01*
X534700Y243000D01*
X538000D01*
X544500Y249500D01*
X564200D01*
X569700Y255000D01*
Y263300D01*
X549500Y283500D01*
Y294000D01*
X544500Y299000D01*
X528500D01*
G01X511500Y206500D02*
Y196622D01*
X513000Y195122D01*
Y174158D01*
X529658Y157500D01*
X538500D01*
X542000Y154000D01*
X584500D01*
X592000Y161500D01*
Y163000D01*
G01X513500Y215500D02*
X510000Y212000D01*
Y208378D01*
X509100Y207478D01*
Y196900D01*
X511500Y194500D01*
Y172829D01*
X529414Y154915D01*
X536085D01*
X539500Y151500D01*
X592000D01*
G01Y141000D02*
X584000Y149000D01*
X541000D01*
X538000Y146000D01*
X528500D01*
X524000Y150500D01*
Y157500D01*
X510000Y171500D01*
Y193500D01*
X507500Y196000D01*
Y208000D01*
X508000Y208500D01*
Y214500D01*
X509000Y215500D01*
G01X539977Y275124D02*
X542277D01*
X543618Y273783D01*
Y266711D01*
X549400Y260929D01*
Y254579D01*
X546325Y251504D01*
X543675D01*
X538171Y246000D01*
X530412D01*
X504000Y219588D01*
Y210330D01*
X502250Y208580D01*
Y202909D01*
X501500Y202159D01*
Y192500D01*
G01X513000Y210500D02*
X514000Y209500D01*
Y203600D01*
X513200Y202800D01*
Y197647D01*
X514500Y196347D01*
Y184501D01*
X543001Y156000D01*
X583000D01*
X589500Y162500D01*
Y170000D01*
X592000Y172500D01*
Y173000D01*
G01X515500Y201000D02*
Y200000D01*
X516500Y199000D01*
Y186500D01*
X539500Y163500D01*
X545000D01*
X550500Y158000D01*
X581500D01*
X587500Y164000D01*
Y178000D01*
X591500Y182000D01*
X601500D01*
X602500Y183000D01*
G01X583000Y297000D02*
X585050Y294950D01*
Y254481D01*
X585764Y253767D01*
Y242237D01*
X589953Y238048D01*
Y236600D01*
G54D18*
G01X402942Y166627D02*
X403973D01*
G02X404337Y166476I0J-514D01*
G01X404385Y166428D01*
G02X404536Y166064I-363J-364D01*
G01Y165782D01*
G02X403786Y165032I-750J0D01*
G01X385150D01*
X384900Y165282D01*
X384813D01*
G01X406879Y166627D02*
X405849D01*
G03X405485Y166476I0J-514D01*
G01X405437Y166428D01*
G03X405286Y166064I363J-364D01*
G01Y165782D01*
G02X403786Y164282I-1500J0D01*
G01X385150D01*
X384900Y164032D01*
X384813D01*
G01X473807Y146942D02*
X472563D01*
G03X472213Y146592I0J-350D01*
G01Y146097D01*
G03X472910Y145400I697J0D01*
G01X476461D01*
X476711Y145650D01*
X476798D01*
G01X469870Y146942D02*
X471113D01*
G02X471463Y146592I0J-350D01*
G01Y146097D01*
G03X472910Y144650I1447J0D01*
G01X476461D01*
X476711Y144400D01*
X476798D01*
G01X402942Y150879D02*
X403774D01*
G02X404536Y150117I0J-762D01*
G01Y138512D01*
G02X404243Y137804I-1002J0D01*
G01X403563Y137124D01*
G03X403050Y135885I1239J-1239D01*
G01Y135337D01*
X402800Y135087D01*
Y135000D01*
G01X406879Y150879D02*
X406048D01*
G03X405286Y150117I0J-762D01*
G01Y138512D01*
G02X404773Y137273I-1752J0D01*
G01X404093Y136593D01*
G03X403800Y135885I709J-708D01*
G01Y135337D01*
X404050Y135087D01*
Y135000D01*
G01X441750Y134313D02*
Y134400D01*
X442000Y134650D01*
Y135500D01*
G03X441717Y136183I-966J0D01*
G01X440671Y137228D01*
X440672D01*
G02X439950Y138971I1742J1743D01*
G01Y144240D01*
G02X441060Y145350I1110J0D01*
G01X447482D01*
G02X448592Y144240I0J-1110D01*
G01Y143355D01*
G03X448942Y143005I350J0D01*
G01X450185D01*
G01X443000Y134313D02*
Y134400D01*
X442750Y134650D01*
Y135501D01*
G03X442248Y136714I-1716J0D01*
G01X441981Y136981D01*
X441980Y136980D01*
X441202Y137759D01*
G02X440700Y138971I1212J1212D01*
G01Y144240D01*
G02X441060Y144600I360J0D01*
G01X447482D01*
G02X447842Y144240I0J-360D01*
G01Y143355D01*
G02X447492Y143005I-350J0D01*
G01X446248D01*
G54D19*
G01X73500Y357500D02*
X73003Y357997D01*
G02X72633Y358589I1091J1094D01*
G01X72550Y359090D01*
Y360350D01*
G02X73170Y360970I620J0D01*
G01X75100D01*
G02X78104Y359725I-1J-4249D01*
G01X80760Y357070D01*
G03X85033Y355300I4273J4273D01*
G01X93410D01*
G03X99020Y360910I0J5610D01*
G01Y362741D01*
G02X99663Y364293I2195J0D01*
G01X105684Y370314D01*
G03X109550Y379650I-9337J9335D01*
G01Y381205D01*
X109600Y381489D01*
G02X109794Y381794I783J-284D01*
G01X110500Y382500D01*
G01X70300Y357500D02*
X70797Y357997D01*
G03X71167Y358589I-1091J1094D01*
G01X71250Y359090D01*
Y360350D01*
G02X73170Y362270I1920J0D01*
G01X75101D01*
G02X79024Y360645I-1J-5549D01*
G01X81680Y357990D01*
G03X85034Y356600I3354J3353D01*
G01X93410D01*
G03X97720Y360910I0J4310D01*
G01Y362741D01*
G02X98743Y365213I3495J1D01*
G01X104764Y371234D01*
G03X108250Y379650I-8416J8416D01*
G01Y381205D01*
X108200Y381489D01*
G03X108006Y381794I-783J-284D01*
G01X107300Y382500D01*
G01X375480Y137400D02*
X349451D01*
G03X346668Y136761I-2J-6372D01*
G03X345811Y136150I1385J-2848D01*
G01X334333Y124672D01*
G03X333721Y123811I2228J-2231D01*
G03X333252Y122470I5684J-2740D01*
G03X333150Y121566I3973J-906D01*
G01Y76720D01*
G02X323230Y66800I-9920J0D01*
G01X321496D01*
G02X321166Y67130I0J330D01*
G03X320836Y67460I-330J0D01*
G01X319016D01*
G03X318686Y67130I0J-330D01*
G02X318356Y66800I-330J0D01*
G01X307496D01*
G02X307166Y67130I0J330D01*
G03X306836Y67460I-330J0D01*
G01X305016D01*
G03X304686Y67130I0J-330D01*
G02X304356Y66800I-330J0D01*
G01X289496D01*
G02X289166Y67130I0J330D01*
G03X288836Y67460I-330J0D01*
G01X287016D01*
G03X286686Y67130I0J-330D01*
G02X286356Y66800I-330J0D01*
G01X275496D01*
G02X275166Y67130I0J330D01*
G03X274836Y67460I-330J0D01*
G01X273016D01*
G03X272686Y67130I0J-330D01*
G02X272356Y66800I-330J0D01*
G01X261526D01*
G02X261201Y67125I0J325D01*
G03X260876Y67450I-325J0D01*
G01X259046D01*
G03X258721Y67125I0J-325D01*
G02X258396Y66800I-325J0D01*
G01X255300D01*
G02X253092Y67392I0J4413D01*
G02X252600Y67770I1190J2057D01*
G01X250058Y70312D01*
G02X249689Y70812I1464J1467D01*
G02X249272Y72500I3204J1687D01*
G01Y74210D01*
G02X250078Y76156I2752J0D01*
G01X250222Y76300D01*
G01X375480Y136100D02*
X349451D01*
G03X347236Y135591I-1J-5072D01*
G03X346731Y135231I816J-1679D01*
G01X335252Y123752D01*
G03X334892Y123246I1308J-1312D01*
G03X334520Y122181I4514J-2174D01*
G03X334450Y121565I2705J-619D01*
G01Y76720D01*
G02X323230Y65500I-11220J0D01*
G01X255301D01*
G02X252441Y66266I-2J5713D01*
G02X251680Y66850I1839J3184D01*
G01X249139Y69392D01*
G02X248538Y70206I2382J2388D01*
G02X247972Y72501I4355J2291D01*
G01Y75093D01*
G03X247790Y75532I-620J0D01*
G01X247022Y76300D01*
G01X376543Y145375D02*
X347028D01*
G03X345747Y145190I-5J-4493D01*
G03X344665Y144544I732J-2455D01*
G01X328742Y128622D01*
G03X328112Y127659I1998J-1994D01*
G03X327720Y125595I5244J-2065D01*
G01Y108865D01*
G02X327400Y108545I-320J0D01*
G03X327080Y108225I0J-320D01*
G01Y106385D01*
G03X327400Y106065I320J0D01*
G02X327720Y105745I0J-320D01*
G01Y87619D01*
G02X327400Y87299I-320J0D01*
G03X327080Y86979I0J-320D01*
G01Y85139D01*
G03X327400Y84819I320J0D01*
G02X327720Y84499I0J-320D01*
G01Y80904D01*
G02X320816Y74000I-6904J0D01*
G01X315404D01*
G02X315074Y74330I0J330D01*
G03X314744Y74660I-330J0D01*
G01X312924D01*
G03X312594Y74330I0J-330D01*
G02X312264Y74000I-330J0D01*
G01X300404D01*
G02X300074Y74330I0J330D01*
G03X299744Y74660I-330J0D01*
G01X297924D01*
G03X297594Y74330I0J-330D01*
G02X297264Y74000I-330J0D01*
G01X295118D01*
G03X293404Y73541I-3J-3417D01*
G02X291691Y73080I-1714J2956D01*
G01X277491D01*
G02X277151Y73420I0J340D01*
G03X276811Y73760I-340J0D01*
G01X275011D01*
G03X274671Y73420I0J-340D01*
G02X274331Y73080I-340J0D01*
G01X269601D01*
G02X268998Y73554I-1J620D01*
G02X268957Y73900I1433J345D01*
G01Y75350D01*
X269907Y76300D01*
G01X376688Y144075D02*
X347027D01*
G03X346118Y143943I-1J-3192D01*
G03X345585Y143625I360J-1209D01*
G01X329662Y127702D01*
G03X329322Y127183I1077J-1076D01*
G03X329020Y125594I4034J-1590D01*
G01Y80904D01*
G02X320816Y72700I-8204J0D01*
G01X295117D01*
G03X294056Y72415I0J-2117D01*
G02X291692Y71780I-2364J4082D01*
G01X269601D01*
G02X267734Y73249I-1J1920D01*
G02X267657Y73901I2697J649D01*
G01Y75350D01*
X266707Y76300D01*
G01X383688Y152265D02*
X382801D01*
G03X381953Y151913I0J-1198D01*
G01X381770Y151730D01*
X381769D01*
X381069Y151030D01*
G02X378338Y149900I-2729J2731D01*
G01X341266D01*
G03X336269Y147830I0J-7067D01*
G01X332361Y143922D01*
G03Y143448I237J-237D01*
G01X332362Y143447D01*
G02Y142973I-237J-237D01*
G01X331082Y141693D01*
G02X330608I-237J237D01*
G01X330607Y141694D01*
G03X330133I-237J-237D01*
G01X324511Y136072D01*
G03X322700Y131700I4372J-4372D01*
G01Y82648D01*
G02X319652Y79600I-3048J0D01*
G01X317540D01*
G03X317205Y79265I0J-335D01*
G02X316870Y78930I-335J0D01*
G01X315060D01*
G02X314725Y79265I0J335D01*
G03X314390Y79600I-335J0D01*
G01X303740D01*
G03X303405Y79265I0J-335D01*
G02X303070Y78930I-335J0D01*
G01X301260D01*
G02X300925Y79265I0J335D01*
G03X300590Y79600I-335J0D01*
G01X289740D01*
G03X289405Y79265I0J-335D01*
G02X289070Y78930I-335J0D01*
G01X287260D01*
G02X286925Y79265I0J335D01*
G03X286590Y79600I-335J0D01*
G01X285305D01*
G03X284105Y78400I0J-1200D01*
G01Y77250D01*
X285055Y76300D01*
G01X383688Y153565D02*
X382800D01*
G03X381033Y152833I0J-2499D01*
G01X380150Y151950D01*
G02X378339Y151200I-1811J1811D01*
G01X341265D01*
G03X335350Y148750I1J-8367D01*
G01X323849Y137249D01*
Y137250D01*
X323591Y136992D01*
Y136991D01*
G03X321400Y131701I5292J-5291D01*
G01Y82648D01*
G02X319652Y80900I-1748J0D01*
G01X285305D01*
G03X282805Y78400I0J-2500D01*
G01Y77250D01*
X281855Y76300D01*
G01X379828Y157600D02*
X366181D01*
G03X365856Y157275I0J-325D01*
G02X365531Y156950I-325J0D01*
G01X363701D01*
G02X363376Y157275I0J325D01*
G03X363051Y157600I-325J0D01*
G01X347579D01*
G03X347254Y157275I0J-325D01*
G02X346929Y156950I-325J0D01*
G01X345099D01*
G02X344774Y157275I0J325D01*
G03X344449Y157600I-325J0D01*
G01X339262D01*
G03X335283Y156663I-1J-8915D01*
G03X334780Y156300I863J-1726D01*
G01X331773Y153293D01*
G03Y152839I227J-227D01*
G02Y152385I-227J-227D01*
G01X330473Y151085D01*
G02X330019I-227J227D01*
G03X329565I-227J-227D01*
G01X321802Y143322D01*
G03Y142862I230J-230D01*
G02Y142402I-230J-230D01*
G01X320508Y141108D01*
G02X320048I-230J230D01*
G03X319588I-230J-230D01*
G01X318091Y139611D01*
G03X317730Y139105I1328J-1329D01*
G03X316870Y135380I7641J-3726D01*
G01Y89923D01*
G02X316650Y88816I-2884J-2D01*
G02X315942Y87758I-3023J1257D01*
G01X315392Y87208D01*
G03X314763Y85689I1519J-1519D01*
G01Y85237D01*
G01X379828Y158900D02*
X339263D01*
G03X334702Y157826I-2J-10215D01*
G03X333860Y157219I1443J-2889D01*
G01X317171Y140531D01*
G03X316561Y139675I2249J-2248D01*
G03X315570Y135381I8810J-4295D01*
G01Y89923D01*
G02X315449Y89314I-1584J-2D01*
G02X315022Y88677I-1821J759D01*
G01X314572Y88227D01*
G02X312817Y87500I-1755J1755D01*
G01X312500D01*
G01X619961Y224474D02*
X620006Y224519D01*
G02X622191Y225424I2185J-2185D01*
G01X622811D01*
G02X624120Y224115I0J-1309D01*
G01Y221350D01*
G02X623335Y219455I-2680J0D01*
G01X622701Y218821D01*
G03X622090Y217343I1479J-1477D01*
G01Y210062D01*
G02X621765Y209737I-325J0D01*
G03X621440Y209412I0J-325D01*
G01Y207582D01*
G03X621765Y207257I325J0D01*
G02X622090Y206932I0J-325D01*
G01Y205102D01*
G02X621765Y204777I-325J0D01*
G03X621440Y204452I0J-325D01*
G01Y202622D01*
G03X621765Y202297I325J0D01*
G02X622090Y201972I0J-325D01*
G01Y200142D01*
G02X621765Y199817I-325J0D01*
G03X621440Y199492I0J-325D01*
G01Y197662D01*
G03X621765Y197337I325J0D01*
G02X622090Y197012I0J-325D01*
G01Y192132D01*
G02X620489Y188267I-5466J0D01*
G01X618037Y185816D01*
G02X617553I-242J242D01*
G03X617069I-242J-242D01*
G01X615799Y184546D01*
G03Y184062I242J-242D01*
G02Y183578I-242J-242D01*
G01X614529Y182308D01*
G02X614045I-242J242D01*
G03X613561I-242J-242D01*
G01X612291Y181038D01*
G03Y180554I242J-242D01*
G02Y180070I-242J-242D01*
G01X611021Y178800D01*
G02X610537I-242J242D01*
G03X610053I-242J-242D01*
G01X608783Y177530D01*
G03Y177046I242J-242D01*
G02Y176562I-242J-242D01*
G01X606277Y174057D01*
G03X603350Y166991I7065J-7066D01*
G01Y159352D01*
G02X603015Y159017I-335J0D01*
G03X602680Y158682I0J-335D01*
G01Y156872D01*
G03X603015Y156537I335J0D01*
G02X603350Y156202I0J-335D01*
G01Y154392D01*
G02X603015Y154057I-335J0D01*
G03X602680Y153722I0J-335D01*
G01Y151912D01*
G03X603015Y151577I335J0D01*
G02X603350Y151242I0J-335D01*
G01Y149432D01*
G02X603015Y149097I-335J0D01*
G03X602680Y148762I0J-335D01*
G01Y146952D01*
G03X603015Y146617I335J0D01*
G02X603350Y146282I0J-335D01*
G01Y138271D01*
G02X598370Y126250I-16999J0D01*
G01X596152Y124031D01*
G03X593400Y117387I6645J-6644D01*
G01Y112795D01*
G02X591188Y107458I-7548J1D01*
G01X578650Y94920D01*
G02X574074Y92598I-5841J5842D01*
G02X573456Y92550I-620J3984D01*
G01X502095D01*
G03X493124Y88834I0J-12687D01*
G01X477500Y73210D01*
G02X469243Y69790I-8257J8257D01*
G01X380544D01*
G02X374136Y72444I0J9063D01*
G01X367472Y79108D01*
G02X364750Y85680I6573J6572D01*
G01Y90587D01*
G02X365077Y91377I1118J0D01*
G01X365700Y92000D01*
G01X362500D02*
X362965Y91535D01*
G02X363450Y90364I-1171J-1171D01*
G01Y85679D01*
G03X366552Y78188I10596J0D01*
G01X373216Y71524D01*
G03X380544Y68490I7327J7329D01*
G01X469242D01*
G03X478420Y72290I3J12977D01*
G01X494043Y87914D01*
G02X502096Y91250I8053J-8051D01*
G01X573457D01*
G03X574274Y91313I0J5332D01*
G03X579570Y94000I-1464J9449D01*
G01X592108Y106538D01*
G03X594700Y112794I-6256J6257D01*
G01Y117386D01*
G02X597072Y123111I8097J-1D01*
G01X599290Y125330D01*
G03X604650Y138270I-12940J12940D01*
G01Y166991D01*
G02X607197Y173137I8692J-1D01*
G01X621409Y187347D01*
G03X623390Y192132I-4785J4784D01*
G01Y217344D01*
G02X623621Y217901I789J-1D01*
G01X624255Y218535D01*
G03X625420Y221350I-2815J2814D01*
G01Y224115D01*
G03X622811Y226724I-2609J0D01*
G01X622191D01*
G02X620006Y227629I0J3090D01*
G01X619961Y227674D01*
G01X365101Y191559D02*
X364482Y190940D01*
G02X363684Y190609I-799J798D01*
G01X362251D01*
G03X360331Y188689I0J-1920D01*
G01Y186160D01*
G03X361251Y183939I3141J0D01*
G01X370130Y175060D01*
G03X373982Y173465I3852J3854D01*
G01X439446D01*
G01Y174765D02*
X435436D01*
G02X435084Y175117I0J352D01*
G01Y175118D01*
G03X434732Y175470I-352J0D01*
G01X432956D01*
G03X432604Y175118I0J-352D01*
G01Y175117D01*
G02X432252Y174765I-352J0D01*
G01X430476D01*
G02X430124Y175117I0J352D01*
G01Y175118D01*
G03X429772Y175470I-352J0D01*
G01X427996D01*
G03X427644Y175118I0J-352D01*
G01Y175117D01*
G02X427292Y174765I-352J0D01*
G01X397125D01*
G02X396788Y175102I0J337D01*
G01Y175103D01*
G03X396451Y175440I-337J0D01*
G01X394645D01*
G03X394308Y175103I0J-337D01*
G01Y175102D01*
G02X393971Y174765I-337J0D01*
G01X390925D01*
G02X390598Y175092I0J327D01*
G01Y175093D01*
G03X390271Y175420I-327J0D01*
G01X388445D01*
G03X388118Y175093I0J-327D01*
G01Y175092D01*
G02X387791Y174765I-327J0D01*
G01X385965D01*
G02X385638Y175092I0J327D01*
G01Y175093D01*
G03X385311Y175420I-327J0D01*
G01X383485D01*
G03X383158Y175093I0J-327D01*
G01Y175092D01*
G02X382831Y174765I-327J0D01*
G01X373983D01*
G02X371050Y175980I0J4148D01*
G01X370255Y176775D01*
G02Y177219I222J222D01*
G01X370256Y177220D01*
G03Y177664I-222J222D01*
G01X368946Y178974D01*
G03X368502I-222J-222D01*
G01X368501Y178973D01*
G02X368057I-222J222D01*
G01X366747Y180283D01*
G02Y180727I222J222D01*
G01X366748Y180728D01*
G03Y181172I-222J222D01*
G01X365438Y182482D01*
G03X364994I-222J-222D01*
G01X364993Y182481D01*
G02X364549I-222J222D01*
G01X362171Y184859D01*
G02X361631Y186160I1300J1302D01*
G01Y188689D01*
G02X362251Y189309I620J0D01*
G01X363661D01*
G02X364497Y188963I0J-1183D01*
G01X365101Y188359D01*
M02*
